(kicad_sch
	(version 20250114)
	(generator "eeschema")
	(generator_version "9.0")
	(paper "A3")
	(title_block
		(title "Artix - Datacenter Secure Control Module (DC-SCM)")
		(date "2024-11-06")
		(rev "1.1.3")
	)
	(text "Status LEDs"
		(exclude_from_sim no)
		(at 31.75 184.15 0)
		(effects
			(font
				(size 2 2)
				(thickness 0.5994)
				(bold yes)
			)
			(justify left bottom)
		)
	)
	(text "DDR3"
		(exclude_from_sim no)
		(at 353.695 142.875 90)
		(effects
			(font
				(size 2 2)
				(thickness 0.5994)
				(bold yes)
			)
			(justify left bottom)
		)
	)
	(text "Configuration modes"
		(exclude_from_sim no)
		(at 109.22 133.35 0)
		(effects
			(font
				(size 2 2)
				(thickness 0.5994)
				(bold yes)
			)
			(justify left bottom)
		)
	)
	(text "FPGA CFG"
		(exclude_from_sim no)
		(at 38.1 63.5 0)
		(effects
			(font
				(size 2 2)
				(thickness 0.5994)
				(bold yes)
			)
			(justify left bottom)
		)
	)
	(text "User LEDs"
		(exclude_from_sim no)
		(at 120.65 215.9 0)
		(effects
			(font
				(size 2 2)
				(thickness 0.5994)
				(bold yes)
			)
			(justify left bottom)
		)
	)
	(junction
		(at 92.71 85.09)
		(diameter 0)
		(color 0 0 0 0)
	)
	(junction
		(at 356.87 57.15)
		(diameter 0)
		(color 0 0 0 0)
	)
	(junction
		(at 63.5 129.54)
		(diameter 0)
		(color 0 0 0 0)
	)
	(junction
		(at 140.97 144.78)
		(diameter 0)
		(color 0 0 0 0)
	)
	(junction
		(at 123.19 135.89)
		(diameter 0)
		(color 0 0 0 0)
	)
	(junction
		(at 63.5 123.19)
		(diameter 0)
		(color 0 0 0 0)
	)
	(junction
		(at 349.25 44.45)
		(diameter 0)
		(color 0 0 0 0)
	)
	(junction
		(at 109.22 96.52)
		(diameter 0)
		(color 0 0 0 0)
	)
	(junction
		(at 63.5 132.08)
		(diameter 0)
		(color 0 0 0 0)
	)
	(junction
		(at 67.31 71.12)
		(diameter 0)
		(color 0 0 0 0)
	)
	(junction
		(at 118.11 114.3)
		(diameter 0)
		(color 0 0 0 0)
	)
	(junction
		(at 356.87 44.45)
		(diameter 0)
		(color 0 0 0 0)
	)
	(junction
		(at 259.08 58.42)
		(diameter 0)
		(color 0 0 0 0)
	)
	(junction
		(at 266.7 58.42)
		(diameter 0)
		(color 0 0 0 0)
	)
	(junction
		(at 63.5 125.73)
		(diameter 0)
		(color 0 0 0 0)
	)
	(junction
		(at 85.09 87.63)
		(diameter 0)
		(color 0 0 0 0)
	)
	(junction
		(at 349.25 57.15)
		(diameter 0)
		(color 0 0 0 0)
	)
	(junction
		(at 77.47 71.12)
		(diameter 0)
		(color 0 0 0 0)
	)
	(junction
		(at 250.19 58.42)
		(diameter 0)
		(color 0 0 0 0)
	)
	(junction
		(at 373.38 44.45)
		(diameter 0)
		(color 0 0 0 0)
	)
	(junction
		(at 140.97 135.89)
		(diameter 0)
		(color 0 0 0 0)
	)
	(junction
		(at 86.36 87.63)
		(diameter 0)
		(color 0 0 0 0)
	)
	(junction
		(at 241.3 58.42)
		(diameter 0)
		(color 0 0 0 0)
	)
	(junction
		(at 118.11 87.63)
		(diameter 0)
		(color 0 0 0 0)
	)
	(junction
		(at 250.19 44.45)
		(diameter 0)
		(color 0 0 0 0)
	)
	(junction
		(at 365.76 44.45)
		(diameter 0)
		(color 0 0 0 0)
	)
	(junction
		(at 109.22 71.12)
		(diameter 0)
		(color 0 0 0 0)
	)
	(junction
		(at 123.19 144.78)
		(diameter 0)
		(color 0 0 0 0)
	)
	(junction
		(at 100.33 71.12)
		(diameter 0)
		(color 0 0 0 0)
	)
	(junction
		(at 92.71 71.12)
		(diameter 0)
		(color 0 0 0 0)
	)
	(junction
		(at 101.6 82.55)
		(diameter 0)
		(color 0 0 0 0)
	)
	(junction
		(at 232.41 44.45)
		(diameter 0)
		(color 0 0 0 0)
	)
	(junction
		(at 63.5 119.38)
		(diameter 0)
		(color 0 0 0 0)
	)
	(junction
		(at 340.36 44.45)
		(diameter 0)
		(color 0 0 0 0)
	)
	(junction
		(at 118.11 104.14)
		(diameter 0)
		(color 0 0 0 0)
	)
	(junction
		(at 85.09 71.12)
		(diameter 0)
		(color 0 0 0 0)
	)
	(junction
		(at 93.98 85.09)
		(diameter 0)
		(color 0 0 0 0)
	)
	(junction
		(at 241.3 44.45)
		(diameter 0)
		(color 0 0 0 0)
	)
	(junction
		(at 332.74 57.15)
		(diameter 0)
		(color 0 0 0 0)
	)
	(junction
		(at 259.08 44.45)
		(diameter 0)
		(color 0 0 0 0)
	)
	(junction
		(at 100.33 82.55)
		(diameter 0)
		(color 0 0 0 0)
	)
	(junction
		(at 340.36 57.15)
		(diameter 0)
		(color 0 0 0 0)
	)
	(no_connect
		(at 331.47 138.43)
	)
	(no_connect
		(at 267.97 161.29)
	)
	(no_connect
		(at 331.47 77.47)
	)
	(wire
		(pts
			(xy 331.47 105.41) (xy 334.01 105.41)
		)
		(stroke
			(width 0)
			(type default)
		)
	)
	(wire
		(pts
			(xy 63.5 129.54) (xy 62.23 129.54)
		)
		(stroke
			(width 0)
			(type default)
		)
	)
	(wire
		(pts
			(xy 331.47 173.99) (xy 334.01 173.99)
		)
		(stroke
			(width 0)
			(type default)
		)
	)
	(wire
		(pts
			(xy 334.01 194.31) (xy 331.47 194.31)
		)
		(stroke
			(width 0)
			(type default)
		)
	)
	(wire
		(pts
			(xy 265.43 113.03) (xy 267.97 113.03)
		)
		(stroke
			(width 0)
			(type default)
		)
	)
	(wire
		(pts
			(xy 250.19 58.42) (xy 250.19 59.69)
		)
		(stroke
			(width 0)
			(type default)
		)
	)
	(wire
		(pts
			(xy 267.97 201.93) (xy 265.43 201.93)
		)
		(stroke
			(width 0)
			(type default)
		)
	)
	(wire
		(pts
			(xy 118.11 87.63) (xy 123.19 87.63)
		)
		(stroke
			(width 0)
			(type default)
		)
	)
	(wire
		(pts
			(xy 63.5 132.08) (xy 63.5 133.35)
		)
		(stroke
			(width 0)
			(type default)
		)
	)
	(wire
		(pts
			(xy 63.5 119.38) (xy 63.5 123.19)
		)
		(stroke
			(width 0)
			(type default)
		)
	)
	(wire
		(pts
			(xy 86.36 87.63) (xy 118.11 87.63)
		)
		(stroke
			(width 0)
			(type default)
		)
	)
	(wire
		(pts
			(xy 349.25 44.45) (xy 340.36 44.45)
		)
		(stroke
			(width 0)
			(type default)
		)
	)
	(wire
		(pts
			(xy 146.05 228.6) (xy 154.94 228.6)
		)
		(stroke
			(width 0)
			(type default)
		)
	)
	(wire
		(pts
			(xy 331.47 95.25) (xy 334.01 95.25)
		)
		(stroke
			(width 0)
			(type default)
		)
	)
	(wire
		(pts
			(xy 331.47 153.67) (xy 334.01 153.67)
		)
		(stroke
			(width 0)
			(type default)
		)
	)
	(wire
		(pts
			(xy 265.43 179.07) (xy 267.97 179.07)
		)
		(stroke
			(width 0)
			(type default)
		)
	)
	(wire
		(pts
			(xy 334.01 199.39) (xy 331.47 199.39)
		)
		(stroke
			(width 0)
			(type default)
		)
	)
	(wire
		(pts
			(xy 78.74 260.35) (xy 81.28 260.35)
		)
		(stroke
			(width 0)
			(type default)
		)
	)
	(wire
		(pts
			(xy 63.5 123.19) (xy 62.23 123.19)
		)
		(stroke
			(width 0)
			(type default)
		)
	)
	(wire
		(pts
			(xy 265.43 77.47) (xy 267.97 77.47)
		)
		(stroke
			(width 0)
			(type default)
		)
	)
	(wire
		(pts
			(xy 331.47 186.69) (xy 334.01 186.69)
		)
		(stroke
			(width 0)
			(type default)
		)
	)
	(wire
		(pts
			(xy 250.19 58.42) (xy 259.08 58.42)
		)
		(stroke
			(width 0)
			(type default)
		)
	)
	(wire
		(pts
			(xy 109.22 96.52) (xy 123.19 96.52)
		)
		(stroke
			(width 0)
			(type default)
		)
	)
	(wire
		(pts
			(xy 265.43 95.25) (xy 267.97 95.25)
		)
		(stroke
			(width 0)
			(type default)
		)
	)
	(wire
		(pts
			(xy 232.41 58.42) (xy 232.41 59.69)
		)
		(stroke
			(width 0)
			(type default)
		)
	)
	(wire
		(pts
			(xy 265.43 163.83) (xy 267.97 163.83)
		)
		(stroke
			(width 0)
			(type default)
		)
	)
	(wire
		(pts
			(xy 265.43 194.31) (xy 267.97 194.31)
		)
		(stroke
			(width 0)
			(type default)
		)
	)
	(wire
		(pts
			(xy 64.77 228.6) (xy 73.66 228.6)
		)
		(stroke
			(width 0)
			(type default)
		)
	)
	(wire
		(pts
			(xy 331.47 82.55) (xy 334.01 82.55)
		)
		(stroke
			(width 0)
			(type default)
		)
	)
	(wire
		(pts
			(xy 100.33 71.12) (xy 109.22 71.12)
		)
		(stroke
			(width 0)
			(type default)
		)
	)
	(wire
		(pts
			(xy 85.09 71.12) (xy 85.09 72.39)
		)
		(stroke
			(width 0)
			(type default)
		)
	)
	(wire
		(pts
			(xy 62.23 99.06) (xy 77.47 99.06)
		)
		(stroke
			(width 0)
			(type default)
		)
	)
	(wire
		(pts
			(xy 265.43 123.19) (xy 267.97 123.19)
		)
		(stroke
			(width 0)
			(type default)
		)
	)
	(wire
		(pts
			(xy 62.23 90.17) (xy 77.47 90.17)
		)
		(stroke
			(width 0)
			(type default)
		)
	)
	(wire
		(pts
			(xy 62.23 93.98) (xy 82.55 93.98)
		)
		(stroke
			(width 0)
			(type default)
		)
	)
	(wire
		(pts
			(xy 146.05 260.35) (xy 146.05 261.62)
		)
		(stroke
			(width 0)
			(type default)
		)
	)
	(wire
		(pts
			(xy 92.71 71.12) (xy 100.33 71.12)
		)
		(stroke
			(width 0)
			(type default)
		)
	)
	(wire
		(pts
			(xy 93.98 88.9) (xy 93.98 85.09)
		)
		(stroke
			(width 0)
			(type default)
		)
	)
	(wire
		(pts
			(xy 331.47 118.11) (xy 334.01 118.11)
		)
		(stroke
			(width 0)
			(type default)
		)
	)
	(wire
		(pts
			(xy 63.5 116.84) (xy 62.23 116.84)
		)
		(stroke
			(width 0)
			(type default)
		)
	)
	(wire
		(pts
			(xy 118.11 87.63) (xy 118.11 104.14)
		)
		(stroke
			(width 0)
			(type default)
		)
	)
	(wire
		(pts
			(xy 331.47 100.33) (xy 334.01 100.33)
		)
		(stroke
			(width 0)
			(type default)
		)
	)
	(wire
		(pts
			(xy 50.8 196.85) (xy 50.8 198.12)
		)
		(stroke
			(width 0)
			(type default)
		)
	)
	(wire
		(pts
			(xy 78.74 228.6) (xy 81.28 228.6)
		)
		(stroke
			(width 0)
			(type default)
		)
	)
	(wire
		(pts
			(xy 373.38 44.45) (xy 365.76 44.45)
		)
		(stroke
			(width 0)
			(type default)
		)
	)
	(wire
		(pts
			(xy 265.43 186.69) (xy 267.97 186.69)
		)
		(stroke
			(width 0)
			(type default)
		)
	)
	(wire
		(pts
			(xy 331.47 148.59) (xy 334.01 148.59)
		)
		(stroke
			(width 0)
			(type default)
		)
	)
	(wire
		(pts
			(xy 109.22 135.89) (xy 109.22 142.24)
		)
		(stroke
			(width 0)
			(type default)
		)
	)
	(wire
		(pts
			(xy 265.43 87.63) (xy 267.97 87.63)
		)
		(stroke
			(width 0)
			(type default)
		)
	)
	(wire
		(pts
			(xy 118.11 114.3) (xy 118.11 115.57)
		)
		(stroke
			(width 0)
			(type default)
		)
	)
	(wire
		(pts
			(xy 265.43 102.87) (xy 267.97 102.87)
		)
		(stroke
			(width 0)
			(type default)
		)
	)
	(wire
		(pts
			(xy 140.97 143.51) (xy 140.97 144.78)
		)
		(stroke
			(width 0)
			(type default)
		)
	)
	(wire
		(pts
			(xy 63.5 71.12) (xy 67.31 71.12)
		)
		(stroke
			(width 0)
			(type default)
		)
	)
	(wire
		(pts
			(xy 265.43 166.37) (xy 267.97 166.37)
		)
		(stroke
			(width 0)
			(type default)
		)
	)
	(wire
		(pts
			(xy 109.22 71.12) (xy 123.19 71.12)
		)
		(stroke
			(width 0)
			(type default)
		)
	)
	(wire
		(pts
			(xy 133.35 238.76) (xy 138.43 238.76)
		)
		(stroke
			(width 0)
			(type default)
		)
	)
	(wire
		(pts
			(xy 265.43 105.41) (xy 267.97 105.41)
		)
		(stroke
			(width 0)
			(type default)
		)
	)
	(wire
		(pts
			(xy 340.36 44.45) (xy 332.74 44.45)
		)
		(stroke
			(width 0)
			(type default)
		)
	)
	(wire
		(pts
			(xy 82.55 96.52) (xy 109.22 96.52)
		)
		(stroke
			(width 0)
			(type default)
		)
	)
	(wire
		(pts
			(xy 38.1 207.01) (xy 43.18 207.01)
		)
		(stroke
			(width 0)
			(type default)
		)
	)
	(wire
		(pts
			(xy 232.41 44.45) (xy 232.41 45.72)
		)
		(stroke
			(width 0)
			(type default)
		)
	)
	(wire
		(pts
			(xy 265.43 135.89) (xy 267.97 135.89)
		)
		(stroke
			(width 0)
			(type default)
		)
	)
	(wire
		(pts
			(xy 331.47 123.19) (xy 334.01 123.19)
		)
		(stroke
			(width 0)
			(type default)
		)
	)
	(wire
		(pts
			(xy 331.47 146.05) (xy 334.01 146.05)
		)
		(stroke
			(width 0)
			(type default)
		)
	)
	(wire
		(pts
			(xy 160.02 228.6) (xy 168.91 228.6)
		)
		(stroke
			(width 0)
			(type default)
		)
	)
	(wire
		(pts
			(xy 331.47 168.91) (xy 334.01 168.91)
		)
		(stroke
			(width 0)
			(type default)
		)
	)
	(wire
		(pts
			(xy 50.8 260.35) (xy 50.8 261.62)
		)
		(stroke
			(width 0)
			(type default)
		)
	)
	(wire
		(pts
			(xy 232.41 58.42) (xy 241.3 58.42)
		)
		(stroke
			(width 0)
			(type default)
		)
	)
	(wire
		(pts
			(xy 331.47 176.53) (xy 334.01 176.53)
		)
		(stroke
			(width 0)
			(type default)
		)
	)
	(wire
		(pts
			(xy 140.97 135.89) (xy 152.4 135.89)
		)
		(stroke
			(width 0)
			(type default)
		)
	)
	(wire
		(pts
			(xy 62.23 85.09) (xy 92.71 85.09)
		)
		(stroke
			(width 0)
			(type default)
		)
	)
	(wire
		(pts
			(xy 265.43 181.61) (xy 267.97 181.61)
		)
		(stroke
			(width 0)
			(type default)
		)
	)
	(wire
		(pts
			(xy 100.33 82.55) (xy 101.6 82.55)
		)
		(stroke
			(width 0)
			(type default)
		)
	)
	(wire
		(pts
			(xy 63.5 78.74) (xy 62.23 78.74)
		)
		(stroke
			(width 0)
			(type default)
		)
	)
	(wire
		(pts
			(xy 265.43 176.53) (xy 267.97 176.53)
		)
		(stroke
			(width 0)
			(type default)
		)
	)
	(wire
		(pts
			(xy 265.43 107.95) (xy 267.97 107.95)
		)
		(stroke
			(width 0)
			(type default)
		)
	)
	(wire
		(pts
			(xy 349.25 44.45) (xy 349.25 45.72)
		)
		(stroke
			(width 0)
			(type default)
		)
	)
	(wire
		(pts
			(xy 63.5 116.84) (xy 63.5 119.38)
		)
		(stroke
			(width 0)
			(type default)
		)
	)
	(wire
		(pts
			(xy 265.43 171.45) (xy 267.97 171.45)
		)
		(stroke
			(width 0)
			(type default)
		)
	)
	(wire
		(pts
			(xy 265.43 196.85) (xy 267.97 196.85)
		)
		(stroke
			(width 0)
			(type default)
		)
	)
	(wire
		(pts
			(xy 331.47 97.79) (xy 334.01 97.79)
		)
		(stroke
			(width 0)
			(type default)
		)
	)
	(wire
		(pts
			(xy 331.47 158.75) (xy 334.01 158.75)
		)
		(stroke
			(width 0)
			(type default)
		)
	)
	(wire
		(pts
			(xy 50.8 260.35) (xy 59.69 260.35)
		)
		(stroke
			(width 0)
			(type default)
		)
	)
	(wire
		(pts
			(xy 332.74 73.66) (xy 331.47 73.66)
		)
		(stroke
			(width 0)
			(type default)
		)
	)
	(wire
		(pts
			(xy 331.47 85.09) (xy 334.01 85.09)
		)
		(stroke
			(width 0)
			(type default)
		)
	)
	(wire
		(pts
			(xy 365.76 44.45) (xy 365.76 45.72)
		)
		(stroke
			(width 0)
			(type default)
		)
	)
	(wire
		(pts
			(xy 62.23 113.03) (xy 77.47 113.03)
		)
		(stroke
			(width 0)
			(type default)
		)
	)
	(wire
		(pts
			(xy 331.47 201.93) (xy 334.01 201.93)
		)
		(stroke
			(width 0)
			(type default)
		)
	)
	(wire
		(pts
			(xy 331.47 130.81) (xy 334.01 130.81)
		)
		(stroke
			(width 0)
			(type default)
		)
	)
	(wire
		(pts
			(xy 259.08 58.42) (xy 259.08 59.69)
		)
		(stroke
			(width 0)
			(type default)
		)
	)
	(wire
		(pts
			(xy 265.43 118.11) (xy 267.97 118.11)
		)
		(stroke
			(width 0)
			(type default)
		)
	)
	(wire
		(pts
			(xy 67.31 71.12) (xy 77.47 71.12)
		)
		(stroke
			(width 0)
			(type default)
		)
	)
	(wire
		(pts
			(xy 62.23 110.49) (xy 77.47 110.49)
		)
		(stroke
			(width 0)
			(type default)
		)
	)
	(wire
		(pts
			(xy 265.43 115.57) (xy 267.97 115.57)
		)
		(stroke
			(width 0)
			(type default)
		)
	)
	(wire
		(pts
			(xy 64.77 196.85) (xy 73.66 196.85)
		)
		(stroke
			(width 0)
			(type default)
		)
	)
	(wire
		(pts
			(xy 266.7 73.66) (xy 267.97 73.66)
		)
		(stroke
			(width 0)
			(type default)
		)
	)
	(wire
		(pts
			(xy 241.3 58.42) (xy 241.3 59.69)
		)
		(stroke
			(width 0)
			(type default)
		)
	)
	(wire
		(pts
			(xy 133.35 270.51) (xy 138.43 270.51)
		)
		(stroke
			(width 0)
			(type default)
		)
	)
	(wire
		(pts
			(xy 331.47 125.73) (xy 334.01 125.73)
		)
		(stroke
			(width 0)
			(type default)
		)
	)
	(wire
		(pts
			(xy 232.41 44.45) (xy 229.87 44.45)
		)
		(stroke
			(width 0)
			(type default)
		)
	)
	(wire
		(pts
			(xy 77.47 77.47) (xy 77.47 90.17)
		)
		(stroke
			(width 0)
			(type default)
		)
	)
	(wire
		(pts
			(xy 265.43 92.71) (xy 267.97 92.71)
		)
		(stroke
			(width 0)
			(type default)
		)
	)
	(wire
		(pts
			(xy 331.47 196.85) (xy 334.01 196.85)
		)
		(stroke
			(width 0)
			(type default)
		)
	)
	(wire
		(pts
			(xy 265.43 184.15) (xy 267.97 184.15)
		)
		(stroke
			(width 0)
			(type default)
		)
	)
	(wire
		(pts
			(xy 331.47 102.87) (xy 334.01 102.87)
		)
		(stroke
			(width 0)
			(type default)
		)
	)
	(polyline
		(pts
			(xy 358.14 204.47) (xy 345.44 204.47)
		)
		(stroke
			(width 0)
			(type default)
		)
	)
	(wire
		(pts
			(xy 109.22 105.41) (xy 109.22 96.52)
		)
		(stroke
			(width 0)
			(type default)
		)
	)
	(wire
		(pts
			(xy 140.97 135.89) (xy 140.97 138.43)
		)
		(stroke
			(width 0)
			(type default)
		)
	)
	(wire
		(pts
			(xy 100.33 77.47) (xy 100.33 82.55)
		)
		(stroke
			(width 0)
			(type default)
		)
	)
	(wire
		(pts
			(xy 331.47 107.95) (xy 334.01 107.95)
		)
		(stroke
			(width 0)
			(type default)
		)
	)
	(wire
		(pts
			(xy 62.23 96.52) (xy 77.47 96.52)
		)
		(stroke
			(width 0)
			(type default)
		)
	)
	(wire
		(pts
			(xy 101.6 82.55) (xy 101.6 88.9)
		)
		(stroke
			(width 0)
			(type default)
		)
	)
	(wire
		(pts
			(xy 173.99 228.6) (xy 176.53 228.6)
		)
		(stroke
			(width 0)
			(type default)
		)
	)
	(wire
		(pts
			(xy 265.43 140.97) (xy 267.97 140.97)
		)
		(stroke
			(width 0)
			(type default)
		)
	)
	(wire
		(pts
			(xy 331.47 80.01) (xy 334.01 80.01)
		)
		(stroke
			(width 0)
			(type default)
		)
	)
	(wire
		(pts
			(xy 349.25 57.15) (xy 349.25 58.42)
		)
		(stroke
			(width 0)
			(type default)
		)
	)
	(wire
		(pts
			(xy 265.43 191.77) (xy 267.97 191.77)
		)
		(stroke
			(width 0)
			(type default)
		)
	)
	(wire
		(pts
			(xy 265.43 168.91) (xy 267.97 168.91)
		)
		(stroke
			(width 0)
			(type default)
		)
	)
	(wire
		(pts
			(xy 38.1 270.51) (xy 43.18 270.51)
		)
		(stroke
			(width 0)
			(type default)
		)
	)
	(wire
		(pts
			(xy 331.47 92.71) (xy 334.01 92.71)
		)
		(stroke
			(width 0)
			(type default)
		)
	)
	(wire
		(pts
			(xy 265.43 133.35) (xy 267.97 133.35)
		)
		(stroke
			(width 0)
			(type default)
		)
	)
	(wire
		(pts
			(xy 50.8 228.6) (xy 59.69 228.6)
		)
		(stroke
			(width 0)
			(type default)
		)
	)
	(wire
		(pts
			(xy 331.47 163.83) (xy 334.01 163.83)
		)
		(stroke
			(width 0)
			(type default)
		)
	)
	(wire
		(pts
			(xy 50.8 228.6) (xy 50.8 229.87)
		)
		(stroke
			(width 0)
			(type default)
		)
	)
	(wire
		(pts
			(xy 331.47 140.97) (xy 334.01 140.97)
		)
		(stroke
			(width 0)
			(type default)
		)
	)
	(wire
		(pts
			(xy 109.22 147.32) (xy 109.22 148.59)
		)
		(stroke
			(width 0)
			(type default)
		)
	)
	(wire
		(pts
			(xy 92.71 71.12) (xy 92.71 72.39)
		)
		(stroke
			(width 0)
			(type default)
		)
	)
	(wire
		(pts
			(xy 331.47 128.27) (xy 334.01 128.27)
		)
		(stroke
			(width 0)
			(type default)
		)
	)
	(wire
		(pts
			(xy 86.36 88.9) (xy 86.36 87.63)
		)
		(stroke
			(width 0)
			(type default)
		)
	)
	(wire
		(pts
			(xy 331.47 115.57) (xy 334.01 115.57)
		)
		(stroke
			(width 0)
			(type default)
		)
	)
	(wire
		(pts
			(xy 92.71 85.09) (xy 93.98 85.09)
		)
		(stroke
			(width 0)
			(type default)
		)
	)
	(wire
		(pts
			(xy 85.09 87.63) (xy 86.36 87.63)
		)
		(stroke
			(width 0)
			(type default)
		)
	)
	(wire
		(pts
			(xy 123.19 144.78) (xy 134.62 144.78)
		)
		(stroke
			(width 0)
			(type default)
		)
	)
	(wire
		(pts
			(xy 92.71 77.47) (xy 92.71 85.09)
		)
		(stroke
			(width 0)
			(type default)
		)
	)
	(wire
		(pts
			(xy 250.19 44.45) (xy 250.19 45.72)
		)
		(stroke
			(width 0)
			(type default)
		)
	)
	(wire
		(pts
			(xy 250.19 44.45) (xy 259.08 44.45)
		)
		(stroke
			(width 0)
			(type default)
		)
	)
	(wire
		(pts
			(xy 373.38 44.45) (xy 373.38 45.72)
		)
		(stroke
			(width 0)
			(type default)
		)
	)
	(wire
		(pts
			(xy 63.5 132.08) (xy 62.23 132.08)
		)
		(stroke
			(width 0)
			(type default)
		)
	)
	(wire
		(pts
			(xy 331.47 184.15) (xy 334.01 184.15)
		)
		(stroke
			(width 0)
			(type default)
		)
	)
	(wire
		(pts
			(xy 375.92 44.45) (xy 373.38 44.45)
		)
		(stroke
			(width 0)
			(type default)
		)
	)
	(wire
		(pts
			(xy 109.22 135.89) (xy 123.19 135.89)
		)
		(stroke
			(width 0)
			(type default)
		)
	)
	(wire
		(pts
			(xy 340.36 44.45) (xy 340.36 45.72)
		)
		(stroke
			(width 0)
			(type default)
		)
	)
	(wire
		(pts
			(xy 331.47 156.21) (xy 334.01 156.21)
		)
		(stroke
			(width 0)
			(type default)
		)
	)
	(wire
		(pts
			(xy 241.3 44.45) (xy 250.19 44.45)
		)
		(stroke
			(width 0)
			(type default)
		)
	)
	(wire
		(pts
			(xy 265.43 85.09) (xy 267.97 85.09)
		)
		(stroke
			(width 0)
			(type default)
		)
	)
	(wire
		(pts
			(xy 101.6 82.55) (xy 123.19 82.55)
		)
		(stroke
			(width 0)
			(type default)
		)
	)
	(wire
		(pts
			(xy 340.36 57.15) (xy 340.36 58.42)
		)
		(stroke
			(width 0)
			(type default)
		)
	)
	(wire
		(pts
			(xy 63.5 129.54) (xy 63.5 132.08)
		)
		(stroke
			(width 0)
			(type default)
		)
	)
	(wire
		(pts
			(xy 109.22 110.49) (xy 109.22 115.57)
		)
		(stroke
			(width 0)
			(type default)
		)
	)
	(wire
		(pts
			(xy 265.43 158.75) (xy 267.97 158.75)
		)
		(stroke
			(width 0)
			(type default)
		)
	)
	(wire
		(pts
			(xy 78.74 196.85) (xy 81.28 196.85)
		)
		(stroke
			(width 0)
			(type default)
		)
	)
	(wire
		(pts
			(xy 266.7 58.42) (xy 266.7 73.66)
		)
		(stroke
			(width 0)
			(type default)
		)
	)
	(wire
		(pts
			(xy 331.47 90.17) (xy 334.01 90.17)
		)
		(stroke
			(width 0)
			(type default)
		)
	)
	(wire
		(pts
			(xy 77.47 71.12) (xy 77.47 72.39)
		)
		(stroke
			(width 0)
			(type default)
		)
	)
	(wire
		(pts
			(xy 356.87 44.45) (xy 356.87 45.72)
		)
		(stroke
			(width 0)
			(type default)
		)
	)
	(wire
		(pts
			(xy 259.08 44.45) (xy 259.08 45.72)
		)
		(stroke
			(width 0)
			(type default)
		)
	)
	(wire
		(pts
			(xy 349.25 57.15) (xy 340.36 57.15)
		)
		(stroke
			(width 0)
			(type default)
		)
	)
	(wire
		(pts
			(xy 62.23 101.6) (xy 77.47 101.6)
		)
		(stroke
			(width 0)
			(type default)
		)
	)
	(wire
		(pts
			(xy 331.47 135.89) (xy 334.01 135.89)
		)
		(stroke
			(width 0)
			(type default)
		)
	)
	(wire
		(pts
			(xy 123.19 143.51) (xy 123.19 144.78)
		)
		(stroke
			(width 0)
			(type default)
		)
	)
	(wire
		(pts
			(xy 265.43 138.43) (xy 267.97 138.43)
		)
		(stroke
			(width 0)
			(type default)
		)
	)
	(wire
		(pts
			(xy 356.87 57.15) (xy 349.25 57.15)
		)
		(stroke
			(width 0)
			(type default)
		)
	)
	(wire
		(pts
			(xy 265.43 80.01) (xy 267.97 80.01)
		)
		(stroke
			(width 0)
			(type default)
		)
	)
	(wire
		(pts
			(xy 331.47 181.61) (xy 334.01 181.61)
		)
		(stroke
			(width 0)
			(type default)
		)
	)
	(wire
		(pts
			(xy 62.23 107.95) (xy 77.47 107.95)
		)
		(stroke
			(width 0)
			(type default)
		)
	)
	(wire
		(pts
			(xy 146.05 260.35) (xy 154.94 260.35)
		)
		(stroke
			(width 0)
			(type default)
		)
	)
	(polyline
		(pts
			(xy 358.14 78.74) (xy 358.14 204.47)
		)
		(stroke
			(width 0)
			(type default)
		)
	)
	(wire
		(pts
			(xy 265.43 189.23) (xy 267.97 189.23)
		)
		(stroke
			(width 0)
			(type default)
		)
	)
	(wire
		(pts
			(xy 331.47 133.35) (xy 334.01 133.35)
		)
		(stroke
			(width 0)
			(type default)
		)
	)
	(wire
		(pts
			(xy 241.3 44.45) (xy 241.3 45.72)
		)
		(stroke
			(width 0)
			(type default)
		)
	)
	(wire
		(pts
			(xy 265.43 97.79) (xy 267.97 97.79)
		)
		(stroke
			(width 0)
			(type default)
		)
	)
	(wire
		(pts
			(xy 265.43 143.51) (xy 267.97 143.51)
		)
		(stroke
			(width 0)
			(type default)
		)
	)
	(wire
		(pts
			(xy 340.36 57.15) (xy 332.74 57.15)
		)
		(stroke
			(width 0)
			(type default)
		)
	)
	(wire
		(pts
			(xy 331.47 191.77) (xy 334.01 191.77)
		)
		(stroke
			(width 0)
			(type default)
		)
	)
	(wire
		(pts
			(xy 265.43 128.27) (xy 267.97 128.27)
		)
		(stroke
			(width 0)
			(type default)
		)
	)
	(wire
		(pts
			(xy 265.43 110.49) (xy 267.97 110.49)
		)
		(stroke
			(width 0)
			(type default)
		)
	)
	(wire
		(pts
			(xy 85.09 77.47) (xy 85.09 87.63)
		)
		(stroke
			(width 0)
			(type default)
		)
	)
	(wire
		(pts
			(xy 109.22 142.24) (xy 107.95 142.24)
		)
		(stroke
			(width 0)
			(type default)
		)
	)
	(wire
		(pts
			(xy 356.87 44.45) (xy 349.25 44.45)
		)
		(stroke
			(width 0)
			(type default)
		)
	)
	(wire
		(pts
			(xy 77.47 71.12) (xy 85.09 71.12)
		)
		(stroke
			(width 0)
			(type default)
		)
	)
	(wire
		(pts
			(xy 93.98 85.09) (xy 123.19 85.09)
		)
		(stroke
			(width 0)
			(type default)
		)
	)
	(wire
		(pts
			(xy 140.97 144.78) (xy 151.13 144.78)
		)
		(stroke
			(width 0)
			(type default)
		)
	)
	(wire
		(pts
			(xy 107.95 147.32) (xy 109.22 147.32)
		)
		(stroke
			(width 0)
			(type default)
		)
	)
	(wire
		(pts
			(xy 365.76 44.45) (xy 356.87 44.45)
		)
		(stroke
			(width 0)
			(type default)
		)
	)
	(wire
		(pts
			(xy 266.7 44.45) (xy 266.7 58.42)
		)
		(stroke
			(width 0)
			(type default)
		)
	)
	(wire
		(pts
			(xy 356.87 57.15) (xy 356.87 58.42)
		)
		(stroke
			(width 0)
			(type default)
		)
	)
	(wire
		(pts
			(xy 331.47 143.51) (xy 334.01 143.51)
		)
		(stroke
			(width 0)
			(type default)
		)
	)
	(wire
		(pts
			(xy 265.43 146.05) (xy 267.97 146.05)
		)
		(stroke
			(width 0)
			(type default)
		)
	)
	(wire
		(pts
			(xy 100.33 71.12) (xy 100.33 72.39)
		)
		(stroke
			(width 0)
			(type default)
		)
	)
	(wire
		(pts
			(xy 331.47 161.29) (xy 334.01 161.29)
		)
		(stroke
			(width 0)
			(type default)
		)
	)
	(wire
		(pts
			(xy 38.1 238.76) (xy 43.18 238.76)
		)
		(stroke
			(width 0)
			(type default)
		)
	)
	(wire
		(pts
			(xy 265.43 100.33) (xy 267.97 100.33)
		)
		(stroke
			(width 0)
			(type default)
		)
	)
	(wire
		(pts
			(xy 160.02 260.35) (xy 168.91 260.35)
		)
		(stroke
			(width 0)
			(type default)
		)
	)
	(wire
		(pts
			(xy 365.76 57.15) (xy 356.87 57.15)
		)
		(stroke
			(width 0)
			(type default)
		)
	)
	(wire
		(pts
			(xy 123.19 135.89) (xy 123.19 138.43)
		)
		(stroke
			(width 0)
			(type default)
		)
	)
	(wire
		(pts
			(xy 265.43 148.59) (xy 267.97 148.59)
		)
		(stroke
			(width 0)
			(type default)
		)
	)
	(wire
		(pts
			(xy 63.5 125.73) (xy 62.23 125.73)
		)
		(stroke
			(width 0)
			(type default)
		)
	)
	(wire
		(pts
			(xy 63.5 78.74) (xy 63.5 71.12)
		)
		(stroke
			(width 0)
			(type default)
		)
	)
	(wire
		(pts
			(xy 146.05 228.6) (xy 146.05 229.87)
		)
		(stroke
			(width 0)
			(type default)
		)
	)
	(wire
		(pts
			(xy 63.5 119.38) (xy 62.23 119.38)
		)
		(stroke
			(width 0)
			(type default)
		)
	)
	(wire
		(pts
			(xy 50.8 196.85) (xy 59.69 196.85)
		)
		(stroke
			(width 0)
			(type default)
		)
	)
	(wire
		(pts
			(xy 259.08 44.45) (xy 266.7 44.45)
		)
		(stroke
			(width 0)
			(type default)
		)
	)
	(wire
		(pts
			(xy 365.76 57.15) (xy 365.76 58.42)
		)
		(stroke
			(width 0)
			(type default)
		)
	)
	(wire
		(pts
			(xy 241.3 58.42) (xy 250.19 58.42)
		)
		(stroke
			(width 0)
			(type default)
		)
	)
	(wire
		(pts
			(xy 123.19 135.89) (xy 140.97 135.89)
		)
		(stroke
			(width 0)
			(type default)
		)
	)
	(wire
		(pts
			(xy 332.74 57.15) (xy 332.74 73.66)
		)
		(stroke
			(width 0)
			(type default)
		)
	)
	(wire
		(pts
			(xy 109.22 71.12) (xy 109.22 72.39)
		)
		(stroke
			(width 0)
			(type default)
		)
	)
	(wire
		(pts
			(xy 63.5 123.19) (xy 63.5 125.73)
		)
		(stroke
			(width 0)
			(type default)
		)
	)
	(wire
		(pts
			(xy 265.43 120.65) (xy 267.97 120.65)
		)
		(stroke
			(width 0)
			(type default)
		)
	)
	(wire
		(pts
			(xy 232.41 44.45) (xy 241.3 44.45)
		)
		(stroke
			(width 0)
			(type default)
		)
	)
	(wire
		(pts
			(xy 62.23 105.41) (xy 77.47 105.41)
		)
		(stroke
			(width 0)
			(type default)
		)
	)
	(wire
		(pts
			(xy 173.99 260.35) (xy 176.53 260.35)
		)
		(stroke
			(width 0)
			(type default)
		)
	)
	(wire
		(pts
			(xy 140.97 144.78) (xy 140.97 146.05)
		)
		(stroke
			(width 0)
			(type default)
		)
	)
	(wire
		(pts
			(xy 331.47 171.45) (xy 334.01 171.45)
		)
		(stroke
			(width 0)
			(type default)
		)
	)
	(wire
		(pts
			(xy 64.77 260.35) (xy 73.66 260.35)
		)
		(stroke
			(width 0)
			(type default)
		)
	)
	(wire
		(pts
			(xy 265.43 125.73) (xy 267.97 125.73)
		)
		(stroke
			(width 0)
			(type default)
		)
	)
	(wire
		(pts
			(xy 265.43 130.81) (xy 267.97 130.81)
		)
		(stroke
			(width 0)
			(type default)
		)
	)
	(wire
		(pts
			(xy 331.47 87.63) (xy 334.01 87.63)
		)
		(stroke
			(width 0)
			(type default)
		)
	)
	(wire
		(pts
			(xy 265.43 173.99) (xy 267.97 173.99)
		)
		(stroke
			(width 0)
			(type default)
		)
	)
	(wire
		(pts
			(xy 331.47 166.37) (xy 334.01 166.37)
		)
		(stroke
			(width 0)
			(type default)
		)
	)
	(wire
		(pts
			(xy 267.97 156.21) (xy 265.43 156.21)
		)
		(stroke
			(width 0)
			(type default)
		)
	)
	(wire
		(pts
			(xy 62.23 82.55) (xy 100.33 82.55)
		)
		(stroke
			(width 0)
			(type default)
		)
	)
	(wire
		(pts
			(xy 62.23 87.63) (xy 85.09 87.63)
		)
		(stroke
			(width 0)
			(type default)
		)
	)
	(wire
		(pts
			(xy 85.09 71.12) (xy 92.71 71.12)
		)
		(stroke
			(width 0)
			(type default)
		)
	)
	(wire
		(pts
			(xy 107.95 144.78) (xy 115.57 144.78)
		)
		(stroke
			(width 0)
			(type default)
		)
	)
	(wire
		(pts
			(xy 332.74 57.15) (xy 332.74 44.45)
		)
		(stroke
			(width 0)
			(type default)
		)
	)
	(wire
		(pts
			(xy 82.55 93.98) (xy 82.55 96.52)
		)
		(stroke
			(width 0)
			(type default)
		)
	)
	(wire
		(pts
			(xy 265.43 90.17) (xy 267.97 90.17)
		)
		(stroke
			(width 0)
			(type default)
		)
	)
	(wire
		(pts
			(xy 331.47 179.07) (xy 334.01 179.07)
		)
		(stroke
			(width 0)
			(type default)
		)
	)
	(wire
		(pts
			(xy 265.43 199.39) (xy 267.97 199.39)
		)
		(stroke
			(width 0)
			(type default)
		)
	)
	(wire
		(pts
			(xy 120.65 114.3) (xy 118.11 114.3)
		)
		(stroke
			(width 0)
			(type default)
		)
	)
	(wire
		(pts
			(xy 123.19 144.78) (xy 123.19 146.05)
		)
		(stroke
			(width 0)
			(type default)
		)
	)
	(wire
		(pts
			(xy 265.43 153.67) (xy 267.97 153.67)
		)
		(stroke
			(width 0)
			(type default)
		)
	)
	(wire
		(pts
			(xy 63.5 125.73) (xy 63.5 129.54)
		)
		(stroke
			(width 0)
			(type default)
		)
	)
	(wire
		(pts
			(xy 331.47 151.13) (xy 334.01 151.13)
		)
		(stroke
			(width 0)
			(type default)
		)
	)
	(wire
		(pts
			(xy 120.65 104.14) (xy 118.11 104.14)
		)
		(stroke
			(width 0)
			(type default)
		)
	)
	(wire
		(pts
			(xy 265.43 82.55) (xy 267.97 82.55)
		)
		(stroke
			(width 0)
			(type default)
		)
	)
	(wire
		(pts
			(xy 331.47 110.49) (xy 334.01 110.49)
		)
		(stroke
			(width 0)
			(type default)
		)
	)
	(wire
		(pts
			(xy 331.47 113.03) (xy 334.01 113.03)
		)
		(stroke
			(width 0)
			(type default)
		)
	)
	(wire
		(pts
			(xy 67.31 71.12) (xy 67.31 72.39)
		)
		(stroke
			(width 0)
			(type default)
		)
	)
	(wire
		(pts
			(xy 334.01 189.23) (xy 331.47 189.23)
		)
		(stroke
			(width 0)
			(type default)
		)
	)
	(polyline
		(pts
			(xy 345.44 78.74) (xy 358.14 78.74)
		)
		(stroke
			(width 0)
			(type default)
		)
	)
	(wire
		(pts
			(xy 109.22 77.47) (xy 109.22 96.52)
		)
		(stroke
			(width 0)
			(type default)
		)
	)
	(wire
		(pts
			(xy 259.08 58.42) (xy 266.7 58.42)
		)
		(stroke
			(width 0)
			(type default)
		)
	)
	(wire
		(pts
			(xy 331.47 120.65) (xy 334.01 120.65)
		)
		(stroke
			(width 0)
			(type default)
		)
	)
	(wire
		(pts
			(xy 265.43 151.13) (xy 267.97 151.13)
		)
		(stroke
			(width 0)
			(type default)
		)
	)
	(label "MODE2"
		(at 115.57 144.78 180)
		(effects
			(font
				(size 1.27 1.27)
			)
			(justify right bottom)
		)
	)
	(label "MODE0"
		(at 151.13 144.78 180)
		(effects
			(font
				(size 1.27 1.27)
			)
			(justify right bottom)
		)
	)
	(label "MODE1"
		(at 77.47 99.06 180)
		(effects
			(font
				(size 1.27 1.27)
			)
			(justify right bottom)
		)
	)
	(label "MODE2"
		(at 77.47 101.6 180)
		(effects
			(font
				(size 1.27 1.27)
			)
			(justify right bottom)
		)
	)
	(label "MODE1"
		(at 134.62 144.78 180)
		(effects
			(font
				(size 1.27 1.27)
			)
			(justify right bottom)
		)
	)
	(label "MODE0"
		(at 77.47 96.52 180)
		(effects
			(font
				(size 1.27 1.27)
			)
			(justify right bottom)
		)
	)
	(global_label "SGPIO0_DI"
		(shape input)
		(at 265.43 138.43 180)
		(fields_autoplaced yes)
		(effects
			(font
				(size 1.27 1.27)
			)
			(justify right)
		)
		(property "Intersheetrefs" "${INTERSHEET_REFS}"
			(at -29.21 26.67 0)
			(effects
				(font
					(size 1.27 1.27)
				)
				(hide yes)
			)
		)
	)
	(global_label "DDR3_RAS"
		(shape input)
		(at 334.01 143.51 0)
		(fields_autoplaced yes)
		(effects
			(font
				(size 1.27 1.27)
			)
			(justify left)
		)
		(property "Intersheetrefs" "${INTERSHEET_REFS}"
			(at -45.085 26.67 0)
			(effects
				(font
					(size 1.27 1.27)
				)
				(justify right)
				(hide yes)
			)
		)
	)
	(global_label "DONE"
		(shape input)
		(at 123.19 82.55 0)
		(fields_autoplaced yes)
		(effects
			(font
				(size 1.27 1.27)
			)
			(justify left)
		)
		(property "Intersheetrefs" "${INTERSHEET_REFS}"
			(at -175.26 -154.94 0)
			(effects
				(font
					(size 1.27 1.27)
				)
				(hide yes)
			)
		)
	)
	(global_label "USR_LED1"
		(shape input)
		(at 133.35 238.76 180)
		(fields_autoplaced yes)
		(effects
			(font
				(size 1.27 1.27)
			)
			(justify right)
		)
		(property "Intersheetrefs" "${INTERSHEET_REFS}"
			(at 29.845 -12.7 0)
			(effects
				(font
					(size 1.27 1.27)
				)
				(hide yes)
			)
		)
	)
	(global_label "ULPI2_DATA6"
		(shape input)
		(at 265.43 125.73 180)
		(fields_autoplaced yes)
		(effects
			(font
				(size 1.27 1.27)
			)
			(justify right)
		)
		(property "Intersheetrefs" "${INTERSHEET_REFS}"
			(at -29.21 26.67 0)
			(effects
				(font
					(size 1.27 1.27)
				)
				(hide yes)
			)
		)
	)
	(global_label "DDR3_DQ15"
		(shape bidirectional)
		(at 334.01 80.01 0)
		(fields_autoplaced yes)
		(effects
			(font
				(size 1.27 1.27)
			)
			(justify left)
		)
		(property "Intersheetrefs" "${INTERSHEET_REFS}"
			(at -44.45 26.67 0)
			(effects
				(font
					(size 1.27 1.27)
				)
				(justify right)
				(hide yes)
			)
		)
	)
	(global_label "VCC1V35"
		(shape input)
		(at 375.92 44.45 0)
		(fields_autoplaced yes)
		(effects
			(font
				(size 1.27 1.27)
			)
			(justify left)
		)
		(property "Intersheetrefs" "${INTERSHEET_REFS}"
			(at 386.5899 44.5294 0)
			(effects
				(font
					(size 1.27 1.27)
				)
				(justify left)
				(hide yes)
			)
		)
	)
	(global_label "DDR3_A0"
		(shape input)
		(at 334.01 158.75 0)
		(fields_autoplaced yes)
		(effects
			(font
				(size 1.27 1.27)
			)
			(justify left)
		)
		(property "Intersheetrefs" "${INTERSHEET_REFS}"
			(at -45.085 26.67 0)
			(effects
				(font
					(size 1.27 1.27)
				)
				(justify right)
				(hide yes)
			)
		)
	)
	(global_label "DDR3_A12"
		(shape input)
		(at 334.01 171.45 0)
		(fields_autoplaced yes)
		(effects
			(font
				(size 1.27 1.27)
			)
			(justify left)
		)
		(property "Intersheetrefs" "${INTERSHEET_REFS}"
			(at -45.085 26.67 0)
			(effects
				(font
					(size 1.27 1.27)
				)
				(justify right)
				(hide yes)
			)
		)
	)
	(global_label "DDR3_BA0"
		(shape input)
		(at 334.01 146.05 0)
		(fields_autoplaced yes)
		(effects
			(font
				(size 1.27 1.27)
			)
			(justify left)
		)
		(property "Intersheetrefs" "${INTERSHEET_REFS}"
			(at -45.085 26.67 0)
			(effects
				(font
					(size 1.27 1.27)
				)
				(justify right)
				(hide yes)
			)
		)
	)
	(global_label "JTAG_TCK"
		(shape input)
		(at 77.47 113.03 0)
		(fields_autoplaced yes)
		(effects
			(font
				(size 1.27 1.27)
			)
			(justify left)
		)
		(property "Intersheetrefs" "${INTERSHEET_REFS}"
			(at -172.085 -106.68 0)
			(effects
				(font
					(size 1.27 1.27)
				)
				(hide yes)
			)
		)
	)
	(global_label "DDR3_DQS1_N"
		(shape bidirectional)
		(at 334.01 92.71 0)
		(fields_autoplaced yes)
		(effects
			(font
				(size 1.27 1.27)
			)
			(justify left)
		)
		(property "Intersheetrefs" "${INTERSHEET_REFS}"
			(at -44.45 26.67 0)
			(effects
				(font
					(size 1.27 1.27)
				)
				(justify right)
				(hide yes)
			)
		)
	)
	(global_label "IRQ_N_R"
		(shape input)
		(at 265.43 113.03 180)
		(fields_autoplaced yes)
		(effects
			(font
				(size 1.27 1.27)
			)
			(justify right)
		)
		(property "Intersheetrefs" "${INTERSHEET_REFS}"
			(at -29.21 26.67 0)
			(effects
				(font
					(size 1.27 1.27)
				)
				(hide yes)
			)
		)
	)
	(global_label "DDR3_A11"
		(shape input)
		(at 334.01 199.39 0)
		(fields_autoplaced yes)
		(effects
			(font
				(size 1.27 1.27)
			)
			(justify left)
		)
		(property "Intersheetrefs" "${INTERSHEET_REFS}"
			(at -45.085 26.67 0)
			(effects
				(font
					(size 1.27 1.27)
				)
				(justify right)
				(hide yes)
			)
		)
	)
	(global_label "ULPI2_CLKOUT"
		(shape input)
		(at 265.43 135.89 180)
		(fields_autoplaced yes)
		(effects
			(font
				(size 1.27 1.27)
			)
			(justify right)
		)
		(property "Intersheetrefs" "${INTERSHEET_REFS}"
			(at -29.21 26.67 0)
			(effects
				(font
					(size 1.27 1.27)
				)
				(hide yes)
			)
		)
	)
	(global_label "DDR3_DQ10"
		(shape bidirectional)
		(at 334.01 105.41 0)
		(fields_autoplaced yes)
		(effects
			(font
				(size 1.27 1.27)
			)
			(justify left)
		)
		(property "Intersheetrefs" "${INTERSHEET_REFS}"
			(at -44.45 26.67 0)
			(effects
				(font
					(size 1.27 1.27)
				)
				(justify right)
				(hide yes)
			)
		)
	)
	(global_label "VCC3V3"
		(shape input)
		(at 229.87 44.45 180)
		(fields_autoplaced yes)
		(effects
			(font
				(size 1.27 1.27)
			)
			(justify right)
		)
		(property "Intersheetrefs" "${INTERSHEET_REFS}"
			(at 220.4096 44.5294 0)
			(effects
				(font
					(size 1.27 1.27)
				)
				(justify right)
				(hide yes)
			)
		)
	)
	(global_label "HPM_FW_RECOVERY_R"
		(shape input)
		(at 265.43 105.41 180)
		(fields_autoplaced yes)
		(effects
			(font
				(size 1.27 1.27)
			)
			(justify right)
		)
		(property "Intersheetrefs" "${INTERSHEET_REFS}"
			(at -29.21 26.67 0)
			(effects
				(font
					(size 1.27 1.27)
				)
				(hide yes)
			)
		)
	)
	(global_label "ULPI2_DATA7"
		(shape input)
		(at 265.43 179.07 180)
		(fields_autoplaced yes)
		(effects
			(font
				(size 1.27 1.27)
			)
			(justify right)
		)
		(property "Intersheetrefs" "${INTERSHEET_REFS}"
			(at -29.21 26.67 0)
			(effects
				(font
					(size 1.27 1.27)
				)
				(hide yes)
			)
		)
	)
	(global_label "JTAG_TMS"
		(shape input)
		(at 77.47 110.49 0)
		(fields_autoplaced yes)
		(effects
			(font
				(size 1.27 1.27)
			)
			(justify left)
		)
		(property "Intersheetrefs" "${INTERSHEET_REFS}"
			(at -172.085 -106.68 0)
			(effects
				(font
					(size 1.27 1.27)
				)
				(hide yes)
			)
		)
	)
	(global_label "ULPI2_DATA5"
		(shape input)
		(at 265.43 128.27 180)
		(fields_autoplaced yes)
		(effects
			(font
				(size 1.27 1.27)
			)
			(justify right)
		)
		(property "Intersheetrefs" "${INTERSHEET_REFS}"
			(at -29.21 26.67 0)
			(effects
				(font
					(size 1.27 1.27)
				)
				(hide yes)
			)
		)
	)
	(global_label "DDR3_ODT"
		(shape input)
		(at 334.01 140.97 0)
		(fields_autoplaced yes)
		(effects
			(font
				(size 1.27 1.27)
			)
			(justify left)
		)
		(property "Intersheetrefs" "${INTERSHEET_REFS}"
			(at -45.085 26.67 0)
			(effects
				(font
					(size 1.27 1.27)
				)
				(justify right)
				(hide yes)
			)
		)
	)
	(global_label "DONE"
		(shape input)
		(at 38.1 238.76 180)
		(fields_autoplaced yes)
		(effects
			(font
				(size 1.27 1.27)
			)
			(justify right)
		)
		(property "Intersheetrefs" "${INTERSHEET_REFS}"
			(at -65.405 17.145 0)
			(effects
				(font
					(size 1.27 1.27)
				)
				(hide yes)
			)
		)
	)
	(global_label "SGPIO_RESET_N"
		(shape input)
		(at 265.43 148.59 180)
		(fields_autoplaced yes)
		(effects
			(font
				(size 1.27 1.27)
			)
			(justify right)
		)
		(property "Intersheetrefs" "${INTERSHEET_REFS}"
			(at -29.21 26.67 0)
			(effects
				(font
					(size 1.27 1.27)
				)
				(hide yes)
			)
		)
	)
	(global_label "DDR3_DM1"
		(shape bidirectional)
		(at 334.01 102.87 0)
		(fields_autoplaced yes)
		(effects
			(font
				(size 1.27 1.27)
			)
			(justify left)
		)
		(property "Intersheetrefs" "${INTERSHEET_REFS}"
			(at -44.45 26.67 0)
			(effects
				(font
					(size 1.27 1.27)
				)
				(justify right)
				(hide yes)
			)
		)
	)
	(global_label "DDR3_A10"
		(shape input)
		(at 334.01 166.37 0)
		(fields_autoplaced yes)
		(effects
			(font
				(size 1.27 1.27)
			)
			(justify left)
		)
		(property "Intersheetrefs" "${INTERSHEET_REFS}"
			(at -45.085 26.67 0)
			(effects
				(font
					(size 1.27 1.27)
				)
				(justify right)
				(hide yes)
			)
		)
	)
	(global_label "ULPI2_DATA2"
		(shape input)
		(at 265.43 115.57 180)
		(fields_autoplaced yes)
		(effects
			(font
				(size 1.27 1.27)
			)
			(justify right)
		)
		(property "Intersheetrefs" "${INTERSHEET_REFS}"
			(at -29.21 26.67 0)
			(effects
				(font
					(size 1.27 1.27)
				)
				(hide yes)
			)
		)
	)
	(global_label "ULPI2_STP"
		(shape input)
		(at 265.43 168.91 180)
		(fields_autoplaced yes)
		(effects
			(font
				(size 1.27 1.27)
			)
			(justify right)
		)
		(property "Intersheetrefs" "${INTERSHEET_REFS}"
			(at -29.21 26.67 0)
			(effects
				(font
					(size 1.27 1.27)
				)
				(hide yes)
			)
		)
	)
	(global_label "DDR3_DQ5"
		(shape bidirectional)
		(at 334.01 130.81 0)
		(fields_autoplaced yes)
		(effects
			(font
				(size 1.27 1.27)
			)
			(justify left)
		)
		(property "Intersheetrefs" "${INTERSHEET_REFS}"
			(at -44.45 26.67 0)
			(effects
				(font
					(size 1.27 1.27)
				)
				(justify right)
				(hide yes)
			)
		)
	)
	(global_label "ULPI2_NXT"
		(shape input)
		(at 265.43 189.23 180)
		(fields_autoplaced yes)
		(effects
			(font
				(size 1.27 1.27)
			)
			(justify right)
		)
		(property "Intersheetrefs" "${INTERSHEET_REFS}"
			(at -29.21 26.67 0)
			(effects
				(font
					(size 1.27 1.27)
				)
				(hide yes)
			)
		)
	)
	(global_label "DDR3_DQ8"
		(shape bidirectional)
		(at 334.01 107.95 0)
		(fields_autoplaced yes)
		(effects
			(font
				(size 1.27 1.27)
			)
			(justify left)
		)
		(property "Intersheetrefs" "${INTERSHEET_REFS}"
			(at -44.45 26.67 0)
			(effects
				(font
					(size 1.27 1.27)
				)
				(justify right)
				(hide yes)
			)
		)
	)
	(global_label "DDR3_CLK_P"
		(shape input)
		(at 334.01 181.61 0)
		(fields_autoplaced yes)
		(effects
			(font
				(size 1.27 1.27)
			)
			(justify left)
		)
		(property "Intersheetrefs" "${INTERSHEET_REFS}"
			(at -45.085 26.67 0)
			(effects
				(font
					(size 1.27 1.27)
				)
				(justify right)
				(hide yes)
			)
		)
	)
	(global_label "DDR3_DQS0_P"
		(shape bidirectional)
		(at 334.01 120.65 0)
		(fields_autoplaced yes)
		(effects
			(font
				(size 1.27 1.27)
			)
			(justify left)
		)
		(property "Intersheetrefs" "${INTERSHEET_REFS}"
			(at -44.45 26.67 0)
			(effects
				(font
					(size 1.27 1.27)
				)
				(justify right)
				(hide yes)
			)
		)
	)
	(global_label "QSPI1_CS0_N"
		(shape input)
		(at 265.43 92.71 180)
		(fields_autoplaced yes)
		(effects
			(font
				(size 1.27 1.27)
			)
			(justify right)
		)
		(property "Intersheetrefs" "${INTERSHEET_REFS}"
			(at -29.21 26.67 0)
			(effects
				(font
					(size 1.27 1.27)
				)
				(hide yes)
			)
		)
	)
	(global_label "DDR3_WE"
		(shape input)
		(at 334.01 153.67 0)
		(fields_autoplaced yes)
		(effects
			(font
				(size 1.27 1.27)
			)
			(justify left)
		)
		(property "Intersheetrefs" "${INTERSHEET_REFS}"
			(at -45.085 26.67 0)
			(effects
				(font
					(size 1.27 1.27)
				)
				(justify right)
				(hide yes)
			)
		)
	)
	(global_label "DDR3_DQ9"
		(shape bidirectional)
		(at 334.01 87.63 0)
		(fields_autoplaced yes)
		(effects
			(font
				(size 1.27 1.27)
			)
			(justify left)
		)
		(property "Intersheetrefs" "${INTERSHEET_REFS}"
			(at -44.45 26.67 0)
			(effects
				(font
					(size 1.27 1.27)
				)
				(justify right)
				(hide yes)
			)
		)
	)
	(global_label "DDR3_DQ0"
		(shape bidirectional)
		(at 334.01 118.11 0)
		(fields_autoplaced yes)
		(effects
			(font
				(size 1.27 1.27)
			)
			(justify left)
		)
		(property "Intersheetrefs" "${INTERSHEET_REFS}"
			(at -44.45 26.67 0)
			(effects
				(font
					(size 1.27 1.27)
				)
				(justify right)
				(hide yes)
			)
		)
	)
	(global_label "VCC3V3"
		(shape input)
		(at 176.53 228.6 0)
		(fields_autoplaced yes)
		(effects
			(font
				(size 1.27 1.27)
			)
			(justify left)
		)
		(property "Intersheetrefs" "${INTERSHEET_REFS}"
			(at -108.585 199.39 0)
			(effects
				(font
					(size 1.27 1.27)
				)
				(hide yes)
			)
		)
	)
	(global_label "RST_PLTRST_BUF_N_R"
		(shape input)
		(at 265.43 100.33 180)
		(fields_autoplaced yes)
		(effects
			(font
				(size 1.27 1.27)
			)
			(justify right)
		)
		(property "Intersheetrefs" "${INTERSHEET_REFS}"
			(at -29.21 26.67 0)
			(effects
				(font
					(size 1.27 1.27)
				)
				(hide yes)
			)
		)
	)
	(global_label "SPARE0_R"
		(shape input)
		(at 265.43 110.49 180)
		(fields_autoplaced yes)
		(effects
			(font
				(size 1.27 1.27)
			)
			(justify right)
		)
		(property "Intersheetrefs" "${INTERSHEET_REFS}"
			(at -29.21 26.67 0)
			(effects
				(font
					(size 1.27 1.27)
				)
				(hide yes)
			)
		)
	)
	(global_label "ULPI2_DATA0"
		(shape input)
		(at 265.43 118.11 180)
		(fields_autoplaced yes)
		(effects
			(font
				(size 1.27 1.27)
			)
			(justify right)
		)
		(property "Intersheetrefs" "${INTERSHEET_REFS}"
			(at -29.21 26.67 0)
			(effects
				(font
					(size 1.27 1.27)
				)
				(hide yes)
			)
		)
	)
	(global_label "I2C[12]_SDA"
		(shape input)
		(at 265.43 181.61 180)
		(fields_autoplaced yes)
		(effects
			(font
				(size 1.27 1.27)
			)
			(justify right)
		)
		(property "Intersheetrefs" "${INTERSHEET_REFS}"
			(at -29.21 26.67 0)
			(effects
				(font
					(size 1.27 1.27)
				)
				(hide yes)
			)
		)
	)
	(global_label "DDR3_A3"
		(shape input)
		(at 334.01 151.13 0)
		(fields_autoplaced yes)
		(effects
			(font
				(size 1.27 1.27)
			)
			(justify left)
		)
		(property "Intersheetrefs" "${INTERSHEET_REFS}"
			(at -45.085 26.67 0)
			(effects
				(font
					(size 1.27 1.27)
				)
				(justify right)
				(hide yes)
			)
		)
	)
	(global_label "ULPI2_DATA1"
		(shape input)
		(at 265.43 123.19 180)
		(fields_autoplaced yes)
		(effects
			(font
				(size 1.27 1.27)
			)
			(justify right)
		)
		(property "Intersheetrefs" "${INTERSHEET_REFS}"
			(at -29.21 26.67 0)
			(effects
				(font
					(size 1.27 1.27)
				)
				(hide yes)
			)
		)
	)
	(global_label "DDR3_DQ4"
		(shape bidirectional)
		(at 334.01 110.49 0)
		(fields_autoplaced yes)
		(effects
			(font
				(size 1.27 1.27)
			)
			(justify left)
		)
		(property "Intersheetrefs" "${INTERSHEET_REFS}"
			(at -44.45 26.67 0)
			(effects
				(font
					(size 1.27 1.27)
				)
				(justify right)
				(hide yes)
			)
		)
	)
	(global_label "DDR3_CLK_N"
		(shape input)
		(at 334.01 184.15 0)
		(fields_autoplaced yes)
		(effects
			(font
				(size 1.27 1.27)
			)
			(justify left)
		)
		(property "Intersheetrefs" "${INTERSHEET_REFS}"
			(at -45.085 26.67 0)
			(effects
				(font
					(size 1.27 1.27)
				)
				(justify right)
				(hide yes)
			)
		)
	)
	(global_label "DDR3_DQ6"
		(shape bidirectional)
		(at 334.01 115.57 0)
		(fields_autoplaced yes)
		(effects
			(font
				(size 1.27 1.27)
			)
			(justify left)
		)
		(property "Intersheetrefs" "${INTERSHEET_REFS}"
			(at -44.45 26.67 0)
			(effects
				(font
					(size 1.27 1.27)
				)
				(justify right)
				(hide yes)
			)
		)
	)
	(global_label "DDR3_DQ13"
		(shape bidirectional)
		(at 334.01 82.55 0)
		(fields_autoplaced yes)
		(effects
			(font
				(size 1.27 1.27)
			)
			(justify left)
		)
		(property "Intersheetrefs" "${INTERSHEET_REFS}"
			(at -44.45 26.67 0)
			(effects
				(font
					(size 1.27 1.27)
				)
				(justify right)
				(hide yes)
			)
		)
	)
	(global_label "CHASI#_R"
		(shape input)
		(at 265.43 120.65 180)
		(fields_autoplaced yes)
		(effects
			(font
				(size 1.27 1.27)
			)
			(justify right)
		)
		(property "Intersheetrefs" "${INTERSHEET_REFS}"
			(at -29.21 26.67 0)
			(effects
				(font
					(size 1.27 1.27)
				)
				(hide yes)
			)
		)
	)
	(global_label "JTAG_TDI"
		(shape input)
		(at 77.47 105.41 0)
		(fields_autoplaced yes)
		(effects
			(font
				(size 1.27 1.27)
			)
			(justify left)
		)
		(property "Intersheetrefs" "${INTERSHEET_REFS}"
			(at -172.085 -106.68 0)
			(effects
				(font
					(size 1.27 1.27)
				)
				(hide yes)
			)
		)
	)
	(global_label "SYS_PWRBTN_N_R"
		(shape input)
		(at 265.43 85.09 180)
		(fields_autoplaced yes)
		(effects
			(font
				(size 1.27 1.27)
			)
			(justify right)
		)
		(property "Intersheetrefs" "${INTERSHEET_REFS}"
			(at -29.21 26.67 0)
			(effects
				(font
					(size 1.27 1.27)
				)
				(hide yes)
			)
		)
	)
	(global_label "HPM_STBY_RST_N_R"
		(shape input)
		(at 265.43 82.55 180)
		(fields_autoplaced yes)
		(effects
			(font
				(size 1.27 1.27)
			)
			(justify right)
		)
		(property "Intersheetrefs" "${INTERSHEET_REFS}"
			(at -29.21 26.67 0)
			(effects
				(font
					(size 1.27 1.27)
				)
				(hide yes)
			)
		)
	)
	(global_label "DDR3_CAS"
		(shape input)
		(at 334.01 148.59 0)
		(fields_autoplaced yes)
		(effects
			(font
				(size 1.27 1.27)
			)
			(justify left)
		)
		(property "Intersheetrefs" "${INTERSHEET_REFS}"
			(at -45.085 26.67 0)
			(effects
				(font
					(size 1.27 1.27)
				)
				(justify right)
				(hide yes)
			)
		)
	)
	(global_label "USR_LED2"
		(shape input)
		(at 133.35 270.51 180)
		(fields_autoplaced yes)
		(effects
			(font
				(size 1.27 1.27)
			)
			(justify right)
		)
		(property "Intersheetrefs" "${INTERSHEET_REFS}"
			(at 29.845 3.81 0)
			(effects
				(font
					(size 1.27 1.27)
				)
				(hide yes)
			)
		)
	)
	(global_label "DDR3_DQ2"
		(shape bidirectional)
		(at 334.01 128.27 0)
		(fields_autoplaced yes)
		(effects
			(font
				(size 1.27 1.27)
			)
			(justify left)
		)
		(property "Intersheetrefs" "${INTERSHEET_REFS}"
			(at -44.45 26.67 0)
			(effects
				(font
					(size 1.27 1.27)
				)
				(justify right)
				(hide yes)
			)
		)
	)
	(global_label "SGPIO_INTR_N"
		(shape input)
		(at 265.43 201.93 180)
		(fields_autoplaced yes)
		(effects
			(font
				(size 1.27 1.27)
			)
			(justify right)
		)
		(property "Intersheetrefs" "${INTERSHEET_REFS}"
			(at -29.21 26.67 0)
			(effects
				(font
					(size 1.27 1.27)
				)
				(hide yes)
			)
		)
	)
	(global_label "I2C[10]_SCL"
		(shape input)
		(at 265.43 156.21 180)
		(fields_autoplaced yes)
		(effects
			(font
				(size 1.27 1.27)
			)
			(justify right)
		)
		(property "Intersheetrefs" "${INTERSHEET_REFS}"
			(at -29.21 26.67 0)
			(effects
				(font
					(size 1.27 1.27)
				)
				(hide yes)
			)
		)
	)
	(global_label "USR_LED0"
		(shape input)
		(at 38.1 270.51 180)
		(fields_autoplaced yes)
		(effects
			(font
				(size 1.27 1.27)
			)
			(justify right)
		)
		(property "Intersheetrefs" "${INTERSHEET_REFS}"
			(at -65.405 34.29 0)
			(effects
				(font
					(size 1.27 1.27)
				)
				(hide yes)
			)
		)
	)
	(global_label "DDR3_A2"
		(shape input)
		(at 334.01 156.21 0)
		(fields_autoplaced yes)
		(effects
			(font
				(size 1.27 1.27)
			)
			(justify left)
		)
		(property "Intersheetrefs" "${INTERSHEET_REFS}"
			(at -45.085 26.67 0)
			(effects
				(font
					(size 1.27 1.27)
				)
				(justify right)
				(hide yes)
			)
		)
	)
	(global_label "DDR3_A8"
		(shape input)
		(at 334.01 191.77 0)
		(fields_autoplaced yes)
		(effects
			(font
				(size 1.27 1.27)
			)
			(justify left)
		)
		(property "Intersheetrefs" "${INTERSHEET_REFS}"
			(at -45.085 26.67 0)
			(effects
				(font
					(size 1.27 1.27)
				)
				(justify right)
				(hide yes)
			)
		)
	)
	(global_label "VCC3V3"
		(shape input)
		(at 123.19 71.12 0)
		(fields_autoplaced yes)
		(effects
			(font
				(size 1.27 1.27)
			)
			(justify left)
		)
		(property "Intersheetrefs" "${INTERSHEET_REFS}"
			(at -130.175 -120.65 0)
			(effects
				(font
					(size 1.27 1.27)
				)
				(hide yes)
			)
		)
	)
	(global_label "DDR3_DQS1_P"
		(shape bidirectional)
		(at 334.01 90.17 0)
		(fields_autoplaced yes)
		(effects
			(font
				(size 1.27 1.27)
			)
			(justify left)
		)
		(property "Intersheetrefs" "${INTERSHEET_REFS}"
			(at -44.45 26.67 0)
			(effects
				(font
					(size 1.27 1.27)
				)
				(justify right)
				(hide yes)
			)
		)
	)
	(global_label "DDR3_BA1"
		(shape input)
		(at 334.01 161.29 0)
		(fields_autoplaced yes)
		(effects
			(font
				(size 1.27 1.27)
			)
			(justify left)
		)
		(property "Intersheetrefs" "${INTERSHEET_REFS}"
			(at -45.085 26.67 0)
			(effects
				(font
					(size 1.27 1.27)
				)
				(justify right)
				(hide yes)
			)
		)
	)
	(global_label "I2C[11]_SDA"
		(shape input)
		(at 265.43 196.85 180)
		(fields_autoplaced yes)
		(effects
			(font
				(size 1.27 1.27)
			)
			(justify right)
		)
		(property "Intersheetrefs" "${INTERSHEET_REFS}"
			(at -29.21 26.67 0)
			(effects
				(font
					(size 1.27 1.27)
				)
				(hide yes)
			)
		)
	)
	(global_label "I2C[9]_SDA"
		(shape input)
		(at 265.43 163.83 180)
		(fields_autoplaced yes)
		(effects
			(font
				(size 1.27 1.27)
			)
			(justify right)
		)
		(property "Intersheetrefs" "${INTERSHEET_REFS}"
			(at -29.21 26.67 0)
			(effects
				(font
					(size 1.27 1.27)
				)
				(hide yes)
			)
		)
	)
	(global_label "DDR3_DQ11"
		(shape bidirectional)
		(at 334.01 97.79 0)
		(fields_autoplaced yes)
		(effects
			(font
				(size 1.27 1.27)
			)
			(justify left)
		)
		(property "Intersheetrefs" "${INTERSHEET_REFS}"
			(at -44.45 26.67 0)
			(effects
				(font
					(size 1.27 1.27)
				)
				(justify right)
				(hide yes)
			)
		)
	)
	(global_label "RoT_CPU_RST_N_R"
		(shape input)
		(at 265.43 102.87 180)
		(fields_autoplaced yes)
		(effects
			(font
				(size 1.27 1.27)
			)
			(justify right)
		)
		(property "Intersheetrefs" "${INTERSHEET_REFS}"
			(at -29.21 26.67 0)
			(effects
				(font
					(size 1.27 1.27)
				)
				(hide yes)
			)
		)
	)
	(global_label "ULPI2_DATA3"
		(shape input)
		(at 265.43 130.81 180)
		(fields_autoplaced yes)
		(effects
			(font
				(size 1.27 1.27)
			)
			(justify right)
		)
		(property "Intersheetrefs" "${INTERSHEET_REFS}"
			(at -29.21 26.67 0)
			(effects
				(font
					(size 1.27 1.27)
				)
				(hide yes)
			)
		)
	)
	(global_label "ULPI2_DATA4"
		(shape input)
		(at 265.43 133.35 180)
		(fields_autoplaced yes)
		(effects
			(font
				(size 1.27 1.27)
			)
			(justify right)
		)
		(property "Intersheetrefs" "${INTERSHEET_REFS}"
			(at -29.21 26.67 0)
			(effects
				(font
					(size 1.27 1.27)
				)
				(hide yes)
			)
		)
	)
	(global_label "SYS_PWROK_R"
		(shape input)
		(at 265.43 107.95 180)
		(fields_autoplaced yes)
		(effects
			(font
				(size 1.27 1.27)
			)
			(justify right)
		)
		(property "Intersheetrefs" "${INTERSHEET_REFS}"
			(at -29.21 26.67 0)
			(effects
				(font
					(size 1.27 1.27)
				)
				(hide yes)
			)
		)
	)
	(global_label "DDR3_A4"
		(shape input)
		(at 334.01 201.93 0)
		(fields_autoplaced yes)
		(effects
			(font
				(size 1.27 1.27)
			)
			(justify left)
		)
		(property "Intersheetrefs" "${INTERSHEET_REFS}"
			(at -45.085 26.67 0)
			(effects
				(font
					(size 1.27 1.27)
				)
				(justify right)
				(hide yes)
			)
		)
	)
	(global_label "DDR3_DQS0_N"
		(shape bidirectional)
		(at 334.01 123.19 0)
		(fields_autoplaced yes)
		(effects
			(font
				(size 1.27 1.27)
			)
			(justify left)
		)
		(property "Intersheetrefs" "${INTERSHEET_REFS}"
			(at -44.45 26.67 0)
			(effects
				(font
					(size 1.27 1.27)
				)
				(justify right)
				(hide yes)
			)
		)
	)
	(global_label "QSPI1_D3"
		(shape input)
		(at 265.43 80.01 180)
		(fields_autoplaced yes)
		(effects
			(font
				(size 1.27 1.27)
			)
			(justify right)
		)
		(property "Intersheetrefs" "${INTERSHEET_REFS}"
			(at -29.21 26.67 0)
			(effects
				(font
					(size 1.27 1.27)
				)
				(hide yes)
			)
		)
	)
	(global_label "SGPIO0_CLK"
		(shape input)
		(at 265.43 153.67 180)
		(fields_autoplaced yes)
		(effects
			(font
				(size 1.27 1.27)
			)
			(justify right)
		)
		(property "Intersheetrefs" "${INTERSHEET_REFS}"
			(at -29.21 26.67 0)
			(effects
				(font
					(size 1.27 1.27)
				)
				(hide yes)
			)
		)
	)
	(global_label "DDR3_DQ14"
		(shape bidirectional)
		(at 334.01 95.25 0)
		(fields_autoplaced yes)
		(effects
			(font
				(size 1.27 1.27)
			)
			(justify left)
		)
		(property "Intersheetrefs" "${INTERSHEET_REFS}"
			(at -44.45 26.67 0)
			(effects
				(font
					(size 1.27 1.27)
				)
				(justify right)
				(hide yes)
			)
		)
	)
	(global_label "VCC3V3"
		(shape input)
		(at 176.53 260.35 0)
		(fields_autoplaced yes)
		(effects
			(font
				(size 1.27 1.27)
			)
			(justify left)
		)
		(property "Intersheetrefs" "${INTERSHEET_REFS}"
			(at -108.585 231.14 0)
			(effects
				(font
					(size 1.27 1.27)
				)
				(hide yes)
			)
		)
	)
	(global_label "QSPI1_CLK"
		(shape input)
		(at 265.43 140.97 180)
		(fields_autoplaced yes)
		(effects
			(font
				(size 1.27 1.27)
			)
			(justify right)
		)
		(property "Intersheetrefs" "${INTERSHEET_REFS}"
			(at -29.21 26.67 0)
			(effects
				(font
					(size 1.27 1.27)
				)
				(hide yes)
			)
		)
	)
	(global_label "PROGRAM"
		(shape input)
		(at 123.19 87.63 0)
		(fields_autoplaced yes)
		(effects
			(font
				(size 1.27 1.27)
			)
			(justify left)
		)
		(property "Intersheetrefs" "${INTERSHEET_REFS}"
			(at -175.26 -154.94 0)
			(effects
				(font
					(size 1.27 1.27)
				)
				(hide yes)
			)
		)
	)
	(global_label "ROT_QSPI_SCK"
		(shape input)
		(at 123.19 96.52 0)
		(fields_autoplaced yes)
		(effects
			(font
				(size 1.27 1.27)
			)
			(justify left)
		)
		(property "Intersheetrefs" "${INTERSHEET_REFS}"
			(at -144.145 -128.27 0)
			(effects
				(font
					(size 1.27 1.27)
				)
				(hide yes)
			)
		)
	)
	(global_label "DDR3_DQ7"
		(shape bidirectional)
		(at 334.01 125.73 0)
		(fields_autoplaced yes)
		(effects
			(font
				(size 1.27 1.27)
			)
			(justify left)
		)
		(property "Intersheetrefs" "${INTERSHEET_REFS}"
			(at -44.45 26.67 0)
			(effects
				(font
					(size 1.27 1.27)
				)
				(justify right)
				(hide yes)
			)
		)
	)
	(global_label "SGPIO0_DO"
		(shape input)
		(at 265.43 158.75 180)
		(fields_autoplaced yes)
		(effects
			(font
				(size 1.27 1.27)
			)
			(justify right)
		)
		(property "Intersheetrefs" "${INTERSHEET_REFS}"
			(at -29.21 26.67 0)
			(effects
				(font
					(size 1.27 1.27)
				)
				(hide yes)
			)
		)
	)
	(global_label "DDR3_CKE"
		(shape input)
		(at 334.01 163.83 0)
		(fields_autoplaced yes)
		(effects
			(font
				(size 1.27 1.27)
			)
			(justify left)
		)
		(property "Intersheetrefs" "${INTERSHEET_REFS}"
			(at -45.085 26.67 0)
			(effects
				(font
					(size 1.27 1.27)
				)
				(justify right)
				(hide yes)
			)
		)
	)
	(global_label "I2C[9]_SCL"
		(shape input)
		(at 265.43 146.05 180)
		(fields_autoplaced yes)
		(effects
			(font
				(size 1.27 1.27)
			)
			(justify right)
		)
		(property "Intersheetrefs" "${INTERSHEET_REFS}"
			(at -29.21 26.67 0)
			(effects
				(font
					(size 1.27 1.27)
				)
				(hide yes)
			)
		)
	)
	(global_label "SGPIO1_DI"
		(shape input)
		(at 265.43 191.77 180)
		(fields_autoplaced yes)
		(effects
			(font
				(size 1.27 1.27)
			)
			(justify right)
		)
		(property "Intersheetrefs" "${INTERSHEET_REFS}"
			(at -29.21 26.67 0)
			(effects
				(font
					(size 1.27 1.27)
				)
				(hide yes)
			)
		)
	)
	(global_label "DDR3_DM0"
		(shape bidirectional)
		(at 334.01 133.35 0)
		(fields_autoplaced yes)
		(effects
			(font
				(size 1.27 1.27)
			)
			(justify left)
		)
		(property "Intersheetrefs" "${INTERSHEET_REFS}"
			(at -44.45 26.67 0)
			(effects
				(font
					(size 1.27 1.27)
				)
				(justify right)
				(hide yes)
			)
		)
	)
	(global_label "DDR3_A13"
		(shape input)
		(at 334.01 186.69 0)
		(fields_autoplaced yes)
		(effects
			(font
				(size 1.27 1.27)
			)
			(justify left)
		)
		(property "Intersheetrefs" "${INTERSHEET_REFS}"
			(at -45.085 26.67 0)
			(effects
				(font
					(size 1.27 1.27)
				)
				(justify right)
				(hide yes)
			)
		)
	)
	(global_label "INIT"
		(shape input)
		(at 123.19 85.09 0)
		(fields_autoplaced yes)
		(effects
			(font
				(size 1.27 1.27)
			)
			(justify left)
		)
		(property "Intersheetrefs" "${INTERSHEET_REFS}"
			(at -175.26 -154.94 0)
			(effects
				(font
					(size 1.27 1.27)
				)
				(hide yes)
			)
		)
	)
	(global_label "DDR3_DQ12"
		(shape bidirectional)
		(at 334.01 85.09 0)
		(fields_autoplaced yes)
		(effects
			(font
				(size 1.27 1.27)
			)
			(justify left)
		)
		(property "Intersheetrefs" "${INTERSHEET_REFS}"
			(at -44.45 26.67 0)
			(effects
				(font
					(size 1.27 1.27)
				)
				(justify right)
				(hide yes)
			)
		)
	)
	(global_label "ULPI2_RESET"
		(shape input)
		(at 265.43 186.69 180)
		(fields_autoplaced yes)
		(effects
			(font
				(size 1.27 1.27)
			)
			(justify right)
		)
		(property "Intersheetrefs" "${INTERSHEET_REFS}"
			(at -29.21 26.67 0)
			(effects
				(font
					(size 1.27 1.27)
				)
				(hide yes)
			)
		)
	)
	(global_label "DDR3_A1"
		(shape input)
		(at 334.01 194.31 0)
		(fields_autoplaced yes)
		(effects
			(font
				(size 1.27 1.27)
			)
			(justify left)
		)
		(property "Intersheetrefs" "${INTERSHEET_REFS}"
			(at -45.085 26.67 0)
			(effects
				(font
					(size 1.27 1.27)
				)
				(justify right)
				(hide yes)
			)
		)
	)
	(global_label "DDR3_BA2"
		(shape input)
		(at 334.01 168.91 0)
		(fields_autoplaced yes)
		(effects
			(font
				(size 1.27 1.27)
			)
			(justify left)
		)
		(property "Intersheetrefs" "${INTERSHEET_REFS}"
			(at -45.085 26.67 0)
			(effects
				(font
					(size 1.27 1.27)
				)
				(justify right)
				(hide yes)
			)
		)
	)
	(global_label "DDR3_DQ3"
		(shape bidirectional)
		(at 334.01 113.03 0)
		(fields_autoplaced yes)
		(effects
			(font
				(size 1.27 1.27)
			)
			(justify left)
		)
		(property "Intersheetrefs" "${INTERSHEET_REFS}"
			(at -44.45 26.67 0)
			(effects
				(font
					(size 1.27 1.27)
				)
				(justify right)
				(hide yes)
			)
		)
	)
	(global_label "DBP_PREQ_N_R"
		(shape input)
		(at 265.43 87.63 180)
		(fields_autoplaced yes)
		(effects
			(font
				(size 1.27 1.27)
			)
			(justify right)
		)
		(property "Intersheetrefs" "${INTERSHEET_REFS}"
			(at -29.21 26.67 0)
			(effects
				(font
					(size 1.27 1.27)
				)
				(hide yes)
			)
		)
	)
	(global_label "DDR3_DQ1"
		(shape bidirectional)
		(at 334.01 135.89 0)
		(fields_autoplaced yes)
		(effects
			(font
				(size 1.27 1.27)
			)
			(justify left)
		)
		(property "Intersheetrefs" "${INTERSHEET_REFS}"
			(at -44.45 26.67 0)
			(effects
				(font
					(size 1.27 1.27)
				)
				(justify right)
				(hide yes)
			)
		)
	)
	(global_label "I2C[12]_SCL"
		(shape input)
		(at 265.43 184.15 180)
		(fields_autoplaced yes)
		(effects
			(font
				(size 1.27 1.27)
			)
			(justify right)
		)
		(property "Intersheetrefs" "${INTERSHEET_REFS}"
			(at -29.21 26.67 0)
			(effects
				(font
					(size 1.27 1.27)
				)
				(hide yes)
			)
		)
	)
	(global_label "DDR3_A5"
		(shape input)
		(at 334.01 179.07 0)
		(fields_autoplaced yes)
		(effects
			(font
				(size 1.27 1.27)
			)
			(justify left)
		)
		(property "Intersheetrefs" "${INTERSHEET_REFS}"
			(at -45.085 26.67 0)
			(effects
				(font
					(size 1.27 1.27)
				)
				(justify right)
				(hide yes)
			)
		)
	)
	(global_label "QSPI1_D0"
		(shape input)
		(at 265.43 90.17 180)
		(fields_autoplaced yes)
		(effects
			(font
				(size 1.27 1.27)
			)
			(justify right)
		)
		(property "Intersheetrefs" "${INTERSHEET_REFS}"
			(at -29.21 26.67 0)
			(effects
				(font
					(size 1.27 1.27)
				)
				(hide yes)
			)
		)
	)
	(global_label "QSPI1_D1"
		(shape input)
		(at 265.43 143.51 180)
		(fields_autoplaced yes)
		(effects
			(font
				(size 1.27 1.27)
			)
			(justify right)
		)
		(property "Intersheetrefs" "${INTERSHEET_REFS}"
			(at -29.21 26.67 0)
			(effects
				(font
					(size 1.27 1.27)
				)
				(hide yes)
			)
		)
	)
	(global_label "DDR3_A6"
		(shape input)
		(at 334.01 173.99 0)
		(fields_autoplaced yes)
		(effects
			(font
				(size 1.27 1.27)
			)
			(justify left)
		)
		(property "Intersheetrefs" "${INTERSHEET_REFS}"
			(at -45.085 26.67 0)
			(effects
				(font
					(size 1.27 1.27)
				)
				(justify right)
				(hide yes)
			)
		)
	)
	(global_label "VCC3V3"
		(shape input)
		(at 152.4 135.89 0)
		(fields_autoplaced yes)
		(effects
			(font
				(size 1.27 1.27)
			)
			(justify left)
		)
		(property "Intersheetrefs" "${INTERSHEET_REFS}"
			(at 320.675 -112.395 0)
			(effects
				(font
					(size 1.27 1.27)
				)
				(justify left)
				(hide yes)
			)
		)
	)
	(global_label "DDR3_RESET"
		(shape input)
		(at 334.01 100.33 0)
		(fields_autoplaced yes)
		(effects
			(font
				(size 1.27 1.27)
			)
			(justify left)
		)
		(property "Intersheetrefs" "${INTERSHEET_REFS}"
			(at -44.45 26.67 0)
			(effects
				(font
					(size 1.27 1.27)
				)
				(justify right)
				(hide yes)
			)
		)
	)
	(global_label "DDR3_A7"
		(shape input)
		(at 334.01 189.23 0)
		(fields_autoplaced yes)
		(effects
			(font
				(size 1.27 1.27)
			)
			(justify left)
		)
		(property "Intersheetrefs" "${INTERSHEET_REFS}"
			(at -45.085 26.67 0)
			(effects
				(font
					(size 1.27 1.27)
				)
				(justify right)
				(hide yes)
			)
		)
	)
	(global_label "I2C[10]_SDA"
		(shape input)
		(at 265.43 151.13 180)
		(fields_autoplaced yes)
		(effects
			(font
				(size 1.27 1.27)
			)
			(justify right)
		)
		(property "Intersheetrefs" "${INTERSHEET_REFS}"
			(at -29.21 26.67 0)
			(effects
				(font
					(size 1.27 1.27)
				)
				(hide yes)
			)
		)
	)
	(global_label "RSVD2"
		(shape input)
		(at 265.43 194.31 180)
		(fields_autoplaced yes)
		(effects
			(font
				(size 1.27 1.27)
			)
			(justify right)
		)
		(property "Intersheetrefs" "${INTERSHEET_REFS}"
			(at -29.21 26.67 0)
			(effects
				(font
					(size 1.27 1.27)
				)
				(hide yes)
			)
		)
	)
	(global_label "VCC3V3"
		(shape input)
		(at 81.28 196.85 0)
		(fields_autoplaced yes)
		(effects
			(font
				(size 1.27 1.27)
			)
			(justify left)
		)
		(property "Intersheetrefs" "${INTERSHEET_REFS}"
			(at -203.835 167.64 0)
			(effects
				(font
					(size 1.27 1.27)
				)
				(hide yes)
			)
		)
	)
	(global_label "ULPI2_DIR"
		(shape input)
		(at 265.43 176.53 180)
		(fields_autoplaced yes)
		(effects
			(font
				(size 1.27 1.27)
			)
			(justify right)
		)
		(property "Intersheetrefs" "${INTERSHEET_REFS}"
			(at -29.21 26.67 0)
			(effects
				(font
					(size 1.27 1.27)
				)
				(hide yes)
			)
		)
	)
	(global_label "SGPIO1_DO"
		(shape input)
		(at 265.43 166.37 180)
		(fields_autoplaced yes)
		(effects
			(font
				(size 1.27 1.27)
			)
			(justify right)
		)
		(property "Intersheetrefs" "${INTERSHEET_REFS}"
			(at -29.21 26.67 0)
			(effects
				(font
					(size 1.27 1.27)
				)
				(hide yes)
			)
		)
	)
	(global_label "JTAG_TDO"
		(shape input)
		(at 77.47 107.95 0)
		(fields_autoplaced yes)
		(effects
			(font
				(size 1.27 1.27)
			)
			(justify left)
		)
		(property "Intersheetrefs" "${INTERSHEET_REFS}"
			(at -172.085 -106.68 0)
			(effects
				(font
					(size 1.27 1.27)
				)
				(hide yes)
			)
		)
	)
	(global_label "VCC3V3"
		(shape input)
		(at 81.28 260.35 0)
		(fields_autoplaced yes)
		(effects
			(font
				(size 1.27 1.27)
			)
			(justify left)
		)
		(property "Intersheetrefs" "${INTERSHEET_REFS}"
			(at -203.835 231.14 0)
			(effects
				(font
					(size 1.27 1.27)
				)
				(hide yes)
			)
		)
	)
	(global_label "SPARE1_R"
		(shape input)
		(at 265.43 97.79 180)
		(fields_autoplaced yes)
		(effects
			(font
				(size 1.27 1.27)
			)
			(justify right)
		)
		(property "Intersheetrefs" "${INTERSHEET_REFS}"
			(at -29.21 26.67 0)
			(effects
				(font
					(size 1.27 1.27)
				)
				(hide yes)
			)
		)
	)
	(global_label "DDR3_A14"
		(shape input)
		(at 334.01 196.85 0)
		(fields_autoplaced yes)
		(effects
			(font
				(size 1.27 1.27)
			)
			(justify left)
		)
		(property "Intersheetrefs" "${INTERSHEET_REFS}"
			(at -45.085 26.67 0)
			(effects
				(font
					(size 1.27 1.27)
				)
				(justify right)
				(hide yes)
			)
		)
	)
	(global_label "DBP_PRDY_N_R"
		(shape input)
		(at 265.43 95.25 180)
		(fields_autoplaced yes)
		(effects
			(font
				(size 1.27 1.27)
			)
			(justify right)
		)
		(property "Intersheetrefs" "${INTERSHEET_REFS}"
			(at -29.21 26.67 0)
			(effects
				(font
					(size 1.27 1.27)
				)
				(hide yes)
			)
		)
	)
	(global_label "I2C[11]_SCL"
		(shape input)
		(at 265.43 173.99 180)
		(fields_autoplaced yes)
		(effects
			(font
				(size 1.27 1.27)
			)
			(justify right)
		)
		(property "Intersheetrefs" "${INTERSHEET_REFS}"
			(at -29.21 26.67 0)
			(effects
				(font
					(size 1.27 1.27)
				)
				(hide yes)
			)
		)
	)
	(global_label "SGPIO1_LD"
		(shape input)
		(at 265.43 199.39 180)
		(fields_autoplaced yes)
		(effects
			(font
				(size 1.27 1.27)
			)
			(justify right)
		)
		(property "Intersheetrefs" "${INTERSHEET_REFS}"
			(at -29.21 26.67 0)
			(effects
				(font
					(size 1.27 1.27)
				)
				(hide yes)
			)
		)
	)
	(global_label "INIT"
		(shape input)
		(at 38.1 207.01 180)
		(fields_autoplaced yes)
		(effects
			(font
				(size 1.27 1.27)
			)
			(justify right)
		)
		(property "Intersheetrefs" "${INTERSHEET_REFS}"
			(at -65.405 -0.635 0)
			(effects
				(font
					(size 1.27 1.27)
				)
				(hide yes)
			)
		)
	)
	(global_label "QSPI1_D2"
		(shape input)
		(at 265.43 77.47 180)
		(fields_autoplaced yes)
		(effects
			(font
				(size 1.27 1.27)
			)
			(justify right)
		)
		(property "Intersheetrefs" "${INTERSHEET_REFS}"
			(at -29.21 26.67 0)
			(effects
				(font
					(size 1.27 1.27)
				)
				(hide yes)
			)
		)
	)
	(global_label "SGPIO0_LD"
		(shape input)
		(at 265.43 171.45 180)
		(fields_autoplaced yes)
		(effects
			(font
				(size 1.27 1.27)
			)
			(justify right)
		)
		(property "Intersheetrefs" "${INTERSHEET_REFS}"
			(at -29.21 26.67 0)
			(effects
				(font
					(size 1.27 1.27)
				)
				(hide yes)
			)
		)
	)
	(global_label "VCC3V3"
		(shape input)
		(at 81.28 228.6 0)
		(fields_autoplaced yes)
		(effects
			(font
				(size 1.27 1.27)
			)
			(justify left)
		)
		(property "Intersheetrefs" "${INTERSHEET_REFS}"
			(at -203.835 199.39 0)
			(effects
				(font
					(size 1.27 1.27)
				)
				(hide yes)
			)
		)
	)
	(global_label "DDR3_A9"
		(shape input)
		(at 334.01 176.53 0)
		(fields_autoplaced yes)
		(effects
			(font
				(size 1.27 1.27)
			)
			(justify left)
		)
		(property "Intersheetrefs" "${INTERSHEET_REFS}"
			(at -45.085 26.67 0)
			(effects
				(font
					(size 1.27 1.27)
				)
				(justify right)
				(hide yes)
			)
		)
	)
	(symbol
		(lib_id "antmicroTestPoints:TP_1mm_SMD")
		(at 101.6 88.9 270)
		(unit 1)
		(exclude_from_sim no)
		(in_bom no)
		(on_board yes)
		(dnp no)
		(property "Reference" "TP2"
			(at 100.33 93.98 90)
			(effects
				(font
					(size 1.27 1.27)
				)
				(justify left)
			)
		)
		(property "Value" "TP_1mm_SMD"
			(at 99.06 88.9 0)
			(effects
				(font
					(size 1.27 1.27)
				)
				(hide yes)
			)
		)
		(property "Footprint" "antmicro-footprints:TP_SMD_1mm"
			(at 91.44 104.14 0)
			(effects
				(font
					(size 1.27 1.27)
					(thickness 0.15)
				)
				(justify left bottom)
				(hide yes)
			)
		)
		(property "Datasheet" ""
			(at 88.9 104.14 0)
			(effects
				(font
					(size 1.27 1.27)
					(thickness 0.15)
				)
				(justify left bottom)
				(hide yes)
			)
		)
		(property "Description" "Test point 1mm SMD"
			(at 101.6 88.9 0)
			(effects
				(font
					(size 1.27 1.27)
				)
				(hide yes)
			)
		)
		(property "MPN" ""
			(at 101.6 88.9 0)
			(effects
				(font
					(size 1.27 1.27)
				)
				(hide yes)
			)
		)
		(property "Manufacturer" ""
			(at 101.6 88.9 0)
			(effects
				(font
					(size 1.27 1.27)
				)
				(hide yes)
			)
		)
		(property "Author" "Antmicro"
			(at 86.36 104.14 0)
			(effects
				(font
					(size 1.27 1.27)
					(thickness 0.15)
				)
				(justify left bottom)
				(hide yes)
			)
		)
		(property "License" "Apache-2.0"
			(at 83.82 104.14 0)
			(effects
				(font
					(size 1.27 1.27)
					(thickness 0.15)
				)
				(justify left bottom)
				(hide yes)
			)
		)
		(pin "1"
		)
		(instances
			(project "artix-dc-scm"
				(path ""
					(reference "TP2")
					(unit 1)
				)
			)
		)
	)
	(symbol
		(lib_id "antmicropower:GND")
		(at 146.05 242.57 0)
		(unit 1)
		(exclude_from_sim no)
		(in_bom yes)
		(on_board yes)
		(dnp no)
		(property "Reference" "#PWR0325"
			(at 146.05 248.92 0)
			(effects
				(font
					(size 1.27 1.27)
				)
				(hide yes)
			)
		)
		(property "Value" "GND"
			(at 146.05 246.38 0)
			(effects
				(font
					(size 1.27 1.27)
				)
			)
		)
		(property "Footprint" ""
			(at 146.05 242.57 0)
			(effects
				(font
					(size 1.27 1.27)
				)
				(hide yes)
			)
		)
		(property "Datasheet" ""
			(at 146.05 242.57 0)
			(effects
				(font
					(size 1.27 1.27)
				)
				(hide yes)
			)
		)
		(property "Description" ""
			(at 146.05 242.57 0)
			(effects
				(font
					(size 1.27 1.27)
				)
				(hide yes)
			)
		)
		(property "Author" "Antmicro"
			(at 154.94 250.19 0)
			(effects
				(font
					(size 1.27 1.27)
					(thickness 0.15)
				)
				(justify left bottom)
				(hide yes)
			)
		)
		(property "License" "Apache-2.0"
			(at 154.94 252.73 0)
			(effects
				(font
					(size 1.27 1.27)
					(thickness 0.15)
				)
				(justify left bottom)
				(hide yes)
			)
		)
		(pin "1"
		)
		(instances
			(project "artix-dc-scm"
				(path ""
					(reference "#PWR0325")
					(unit 1)
				)
			)
		)
	)
	(symbol
		(lib_id "antmicroFPGAChips:XC7A100T-FGG484")
		(at 267.97 73.66 0)
		(unit 3)
		(exclude_from_sim no)
		(in_bom yes)
		(on_board yes)
		(dnp no)
		(fields_autoplaced yes)
		(property "Reference" "U14"
			(at 299.72 63.5 0)
			(effects
				(font
					(size 1.27 1.27)
					(thickness 0.15)
				)
			)
		)
		(property "Value" "XC7A100T-FGG484"
			(at 299.72 66.04 0)
			(effects
				(font
					(size 1.27 1.27)
					(thickness 0.15)
				)
			)
		)
		(property "Footprint" "antmicro-footprints:BGA-484_23x23mm_Layout22x22_P1mm_FGG484"
			(at 323.85 81.28 0)
			(effects
				(font
					(size 1.27 1.27)
					(thickness 0.15)
				)
				(justify left bottom)
				(hide yes)
			)
		)
		(property "Datasheet" "https://docs.xilinx.com/v/u/en-US/ds181_Artix_7_Data_Sheet"
			(at 323.85 83.82 0)
			(effects
				(font
					(size 1.27 1.27)
					(thickness 0.15)
				)
				(justify left bottom)
				(hide yes)
			)
		)
		(property "Description" "Artix-7 Field Programmable Gate Array IC 210 324-LFBGA, CSPBGA"
			(at 267.97 73.66 0)
			(effects
				(font
					(size 1.27 1.27)
				)
				(hide yes)
			)
		)
		(property "MPN" "XC7A100T-FGG484"
			(at 323.85 86.36 0)
			(effects
				(font
					(size 1.27 1.27)
					(thickness 0.15)
				)
				(justify left bottom)
				(hide yes)
			)
		)
		(property "Manufacturer" "AMD-Xilinx"
			(at 323.85 88.9 0)
			(effects
				(font
					(size 1.27 1.27)
					(thickness 0.15)
				)
				(justify left bottom)
				(hide yes)
			)
		)
		(property "Author" "Antmicro"
			(at 323.85 91.44 0)
			(effects
				(font
					(size 1.27 1.27)
					(thickness 0.15)
				)
				(justify left bottom)
				(hide yes)
			)
		)
		(property "License" "Apache-2.0"
			(at 323.85 93.98 0)
			(effects
				(font
					(size 1.27 1.27)
					(thickness 0.15)
				)
				(justify left bottom)
				(hide yes)
			)
		)
		(pin "AA10"
		)
		(pin "AA11"
		)
		(pin "AA13"
		)
		(pin "AA14"
		)
		(pin "AA15"
		)
		(pin "AA16"
		)
		(pin "AA17"
		)
		(pin "AA9"
		)
		(pin "AB10"
		)
		(pin "AB11"
		)
		(pin "AB12"
		)
		(pin "AB13"
		)
		(pin "AB14"
		)
		(pin "AB15"
		)
		(pin "AB16"
		)
		(pin "AB17"
		)
		(pin "T14"
		)
		(pin "T15"
		)
		(pin "T16"
		)
		(pin "U15"
		)
		(pin "U16"
		)
		(pin "V10"
		)
		(pin "V13"
		)
		(pin "V14"
		)
		(pin "V15"
		)
		(pin "V16"
		)
		(pin "W10"
		)
		(pin "W11"
		)
		(pin "W12"
		)
		(pin "W13"
		)
		(pin "W14"
		)
		(pin "W15"
		)
		(pin "W16"
		)
		(pin "Y10"
		)
		(pin "Y11"
		)
		(pin "Y12"
		)
		(pin "Y13"
		)
		(pin "Y14"
		)
		(pin "Y16"
		)
		(pin "Y17"
		)
		(pin "AA18"
		)
		(pin "AA19"
		)
		(pin "AA20"
		)
		(pin "AA21"
		)
		(pin "AB18"
		)
		(pin "AB20"
		)
		(pin "AB21"
		)
		(pin "AB22"
		)
		(pin "M14"
		)
		(pin "N13"
		)
		(pin "N14"
		)
		(pin "N15"
		)
		(pin "N17"
		)
		(pin "P14"
		)
		(pin "P15"
		)
		(pin "P16"
		)
		(pin "P17"
		)
		(pin "P18"
		)
		(pin "P19"
		)
		(pin "P20"
		)
		(pin "P21"
		)
		(pin "P22"
		)
		(pin "R14"
		)
		(pin "R15"
		)
		(pin "R16"
		)
		(pin "R17"
		)
		(pin "R18"
		)
		(pin "R19"
		)
		(pin "R21"
		)
		(pin "R22"
		)
		(pin "T18"
		)
		(pin "T19"
		)
		(pin "T20"
		)
		(pin "T21"
		)
		(pin "T22"
		)
		(pin "U17"
		)
		(pin "U18"
		)
		(pin "U19"
		)
		(pin "U20"
		)
		(pin "U21"
		)
		(pin "U22"
		)
		(pin "V17"
		)
		(pin "V18"
		)
		(pin "V19"
		)
		(pin "V20"
		)
		(pin "V22"
		)
		(pin "W17"
		)
		(pin "W19"
		)
		(pin "W20"
		)
		(pin "W21"
		)
		(pin "W22"
		)
		(pin "Y18"
		)
		(pin "Y19"
		)
		(pin "Y20"
		)
		(pin "Y21"
		)
		(pin "Y22"
		)
		(pin "G13"
		)
		(pin "G15"
		)
		(pin "G16"
		)
		(pin "G17"
		)
		(pin "G18"
		)
		(pin "G19"
		)
		(pin "G20"
		)
		(pin "H13"
		)
		(pin "H14"
		)
		(pin "H15"
		)
		(pin "H16"
		)
		(pin "H17"
		)
		(pin "H18"
		)
		(pin "H19"
		)
		(pin "H20"
		)
		(pin "H22"
		)
		(pin "J13"
		)
		(pin "J14"
		)
		(pin "J15"
		)
		(pin "J16"
		)
		(pin "J17"
		)
		(pin "J19"
		)
		(pin "J20"
		)
		(pin "J21"
		)
		(pin "J22"
		)
		(pin "K13"
		)
		(pin "K14"
		)
		(pin "K16"
		)
		(pin "K17"
		)
		(pin "K18"
		)
		(pin "K19"
		)
		(pin "K20"
		)
		(pin "K21"
		)
		(pin "K22"
		)
		(pin "L13"
		)
		(pin "L14"
		)
		(pin "L15"
		)
		(pin "L16"
		)
		(pin "L17"
		)
		(pin "L18"
		)
		(pin "L19"
		)
		(pin "L20"
		)
		(pin "L21"
		)
		(pin "M13"
		)
		(pin "M15"
		)
		(pin "M16"
		)
		(pin "M17"
		)
		(pin "M18"
		)
		(pin "M20"
		)
		(pin "M21"
		)
		(pin "M22"
		)
		(pin "N18"
		)
		(pin "N19"
		)
		(pin "N20"
		)
		(pin "N21"
		)
		(pin "N22"
		)
		(pin "A13"
		)
		(pin "A14"
		)
		(pin "A15"
		)
		(pin "A16"
		)
		(pin "A17"
		)
		(pin "A18"
		)
		(pin "A19"
		)
		(pin "A20"
		)
		(pin "A21"
		)
		(pin "B13"
		)
		(pin "B14"
		)
		(pin "B15"
		)
		(pin "B16"
		)
		(pin "B17"
		)
		(pin "B18"
		)
		(pin "B20"
		)
		(pin "B21"
		)
		(pin "B22"
		)
		(pin "C13"
		)
		(pin "C14"
		)
		(pin "C15"
		)
		(pin "C17"
		)
		(pin "C18"
		)
		(pin "C19"
		)
		(pin "C20"
		)
		(pin "C21"
		)
		(pin "C22"
		)
		(pin "D14"
		)
		(pin "D15"
		)
		(pin "D16"
		)
		(pin "D17"
		)
		(pin "D18"
		)
		(pin "D19"
		)
		(pin "D20"
		)
		(pin "D21"
		)
		(pin "D22"
		)
		(pin "E13"
		)
		(pin "E14"
		)
		(pin "E15"
		)
		(pin "E16"
		)
		(pin "E17"
		)
		(pin "E18"
		)
		(pin "E19"
		)
		(pin "E21"
		)
		(pin "E22"
		)
		(pin "F13"
		)
		(pin "F14"
		)
		(pin "F15"
		)
		(pin "F16"
		)
		(pin "F18"
		)
		(pin "F19"
		)
		(pin "F20"
		)
		(pin "F21"
		)
		(pin "F22"
		)
		(pin "G21"
		)
		(pin "G22"
		)
		(pin "AA1"
		)
		(pin "AA3"
		)
		(pin "AA4"
		)
		(pin "AA5"
		)
		(pin "AA6"
		)
		(pin "AA7"
		)
		(pin "AA8"
		)
		(pin "AB1"
		)
		(pin "AB2"
		)
		(pin "AB3"
		)
		(pin "AB4"
		)
		(pin "AB5"
		)
		(pin "AB6"
		)
		(pin "AB7"
		)
		(pin "AB8"
		)
		(pin "R2"
		)
		(pin "R3"
		)
		(pin "R4"
		)
		(pin "R5"
		)
		(pin "R6"
		)
		(pin "T1"
		)
		(pin "T2"
		)
		(pin "T3"
		)
		(pin "T4"
		)
		(pin "T5"
		)
		(pin "T6"
		)
		(pin "U1"
		)
		(pin "U2"
		)
		(pin "U3"
		)
		(pin "U5"
		)
		(pin "U6"
		)
		(pin "U7"
		)
		(pin "V2"
		)
		(pin "V3"
		)
		(pin "V4"
		)
		(pin "V5"
		)
		(pin "V6"
		)
		(pin "V7"
		)
		(pin "V8"
		)
		(pin "V9"
		)
		(pin "W1"
		)
		(pin "W2"
		)
		(pin "W3"
		)
		(pin "W4"
		)
		(pin "W5"
		)
		(pin "W6"
		)
		(pin "W7"
		)
		(pin "W9"
		)
		(pin "Y1"
		)
		(pin "Y2"
		)
		(pin "Y3"
		)
		(pin "Y4"
		)
		(pin "Y6"
		)
		(pin "Y7"
		)
		(pin "Y8"
		)
		(pin "Y9"
		)
		(pin "A1"
		)
		(pin "B1"
		)
		(pin "B2"
		)
		(pin "C1"
		)
		(pin "C2"
		)
		(pin "D1"
		)
		(pin "D2"
		)
		(pin "E1"
		)
		(pin "E2"
		)
		(pin "E3"
		)
		(pin "F1"
		)
		(pin "F2"
		)
		(pin "F3"
		)
		(pin "F4"
		)
		(pin "G1"
		)
		(pin "G2"
		)
		(pin "G3"
		)
		(pin "G4"
		)
		(pin "H2"
		)
		(pin "H3"
		)
		(pin "H4"
		)
		(pin "H5"
		)
		(pin "H6"
		)
		(pin "J1"
		)
		(pin "J2"
		)
		(pin "J3"
		)
		(pin "J4"
		)
		(pin "J5"
		)
		(pin "J6"
		)
		(pin "K1"
		)
		(pin "K2"
		)
		(pin "K3"
		)
		(pin "K4"
		)
		(pin "K6"
		)
		(pin "L1"
		)
		(pin "L3"
		)
		(pin "L4"
		)
		(pin "L5"
		)
		(pin "L6"
		)
		(pin "M1"
		)
		(pin "M2"
		)
		(pin "M3"
		)
		(pin "M4"
		)
		(pin "M5"
		)
		(pin "M6"
		)
		(pin "N1"
		)
		(pin "N2"
		)
		(pin "N3"
		)
		(pin "N4"
		)
		(pin "N5"
		)
		(pin "P1"
		)
		(pin "P2"
		)
		(pin "P4"
		)
		(pin "P5"
		)
		(pin "P6"
		)
		(pin "R1"
		)
		(pin "F12"
		)
		(pin "G11"
		)
		(pin "L10"
		)
		(pin "L12"
		)
		(pin "L9"
		)
		(pin "M10"
		)
		(pin "M9"
		)
		(pin "N10"
		)
		(pin "N12"
		)
		(pin "N9"
		)
		(pin "R13"
		)
		(pin "T12"
		)
		(pin "T13"
		)
		(pin "U10"
		)
		(pin "U11"
		)
		(pin "U12"
		)
		(pin "U13"
		)
		(pin "U8"
		)
		(pin "U9"
		)
		(pin "V12"
		)
		(pin "A10"
		)
		(pin "A4"
		)
		(pin "A6"
		)
		(pin "A8"
		)
		(pin "B10"
		)
		(pin "B11"
		)
		(pin "B4"
		)
		(pin "B5"
		)
		(pin "B6"
		)
		(pin "B7"
		)
		(pin "B8"
		)
		(pin "B9"
		)
		(pin "C11"
		)
		(pin "C4"
		)
		(pin "C5"
		)
		(pin "C7"
		)
		(pin "C8"
		)
		(pin "C9"
		)
		(pin "D10"
		)
		(pin "D11"
		)
		(pin "D5"
		)
		(pin "D6"
		)
		(pin "D7"
		)
		(pin "D9"
		)
		(pin "E10"
		)
		(pin "E6"
		)
		(pin "E8"
		)
		(pin "F10"
		)
		(pin "F6"
		)
		(pin "F7"
		)
		(pin "F8"
		)
		(pin "F9"
		)
		(pin "A11"
		)
		(pin "A12"
		)
		(pin "A2"
		)
		(pin "A22"
		)
		(pin "A3"
		)
		(pin "A5"
		)
		(pin "A7"
		)
		(pin "A9"
		)
		(pin "AA12"
		)
		(pin "AA2"
		)
		(pin "AA22"
		)
		(pin "AB19"
		)
		(pin "AB9"
		)
		(pin "B12"
		)
		(pin "B19"
		)
		(pin "B3"
		)
		(pin "C10"
		)
		(pin "C12"
		)
		(pin "C16"
		)
		(pin "C3"
		)
		(pin "C6"
		)
		(pin "D12"
		)
		(pin "D13"
		)
		(pin "D3"
		)
		(pin "D4"
		)
		(pin "D8"
		)
		(pin "E11"
		)
		(pin "E12"
		)
		(pin "E20"
		)
		(pin "E4"
		)
		(pin "E5"
		)
		(pin "E7"
		)
		(pin "E9"
		)
		(pin "F11"
		)
		(pin "F17"
		)
		(pin "F5"
		)
		(pin "G10"
		)
		(pin "G12"
		)
		(pin "G14"
		)
		(pin "G5"
		)
		(pin "G6"
		)
		(pin "G7"
		)
		(pin "G8"
		)
		(pin "G9"
		)
		(pin "H1"
		)
		(pin "H10"
		)
		(pin "H11"
		)
		(pin "H12"
		)
		(pin "H21"
		)
		(pin "H7"
		)
		(pin "H8"
		)
		(pin "H9"
		)
		(pin "J10"
		)
		(pin "J11"
		)
		(pin "J12"
		)
		(pin "J18"
		)
		(pin "J7"
		)
		(pin "J8"
		)
		(pin "J9"
		)
		(pin "K10"
		)
		(pin "K11"
		)
		(pin "K12"
		)
		(pin "K15"
		)
		(pin "K5"
		)
		(pin "K7"
		)
		(pin "K8"
		)
		(pin "K9"
		)
		(pin "L11"
		)
		(pin "L2"
		)
		(pin "L22"
		)
		(pin "L7"
		)
		(pin "L8"
		)
		(pin "M11"
		)
		(pin "M12"
		)
		(pin "M19"
		)
		(pin "M7"
		)
		(pin "M8"
		)
		(pin "N11"
		)
		(pin "N16"
		)
		(pin "N6"
		)
		(pin "N7"
		)
		(pin "N8"
		)
		(pin "P10"
		)
		(pin "P11"
		)
		(pin "P12"
		)
		(pin "P13"
		)
		(pin "P3"
		)
		(pin "P7"
		)
		(pin "P8"
		)
		(pin "P9"
		)
		(pin "R10"
		)
		(pin "R11"
		)
		(pin "R12"
		)
		(pin "R20"
		)
		(pin "R7"
		)
		(pin "R8"
		)
		(pin "R9"
		)
		(pin "T10"
		)
		(pin "T11"
		)
		(pin "T17"
		)
		(pin "T7"
		)
		(pin "T8"
		)
		(pin "T9"
		)
		(pin "U14"
		)
		(pin "U4"
		)
		(pin "V1"
		)
		(pin "V11"
		)
		(pin "V21"
		)
		(pin "W18"
		)
		(pin "W8"
		)
		(pin "Y15"
		)
		(pin "Y5"
		)
		(instances
			(project "artix-dc-scm"
				(path ""
					(reference "U14")
					(unit 3)
				)
			)
		)
	)
	(symbol
		(lib_id "antmicroResistors0402:R_1k_0402")
		(at 73.66 228.6 0)
		(unit 1)
		(exclude_from_sim no)
		(in_bom yes)
		(on_board yes)
		(dnp no)
		(property "Reference" "R129"
			(at 76.2 226.06 0)
			(effects
				(font
					(size 1.27 1.27)
				)
			)
		)
		(property "Value" "R_1k_0402"
			(at 93.98 241.3 0)
			(effects
				(font
					(size 1.27 1.27)
					(thickness 0.15)
				)
				(justify left bottom)
				(hide yes)
			)
		)
		(property "Footprint" "antmicro-footprints:R_0402_1005Metric"
			(at 93.98 243.84 0)
			(effects
				(font
					(size 1.27 1.27)
					(thickness 0.15)
				)
				(justify left bottom)
				(hide yes)
			)
		)
		(property "Datasheet" "https://www.bourns.com/docs/product-datasheets/cr.pdf"
			(at 93.98 246.38 0)
			(effects
				(font
					(size 1.27 1.27)
					(thickness 0.15)
				)
				(justify left bottom)
				(hide yes)
			)
		)
		(property "Description" "SMD Chip Resistor, 1 kohm, ± 1%, 63 mW, 0402 [1005 Metric], Thick Film, General Purpose"
			(at 73.66 228.6 0)
			(effects
				(font
					(size 1.27 1.27)
				)
				(hide yes)
			)
		)
		(property "Manufacturer" "Bourns"
			(at 93.98 251.46 0)
			(effects
				(font
					(size 1.27 1.27)
					(thickness 0.15)
				)
				(justify left bottom)
				(hide yes)
			)
		)
		(property "MPN" "CR0402-FX-1001GLF"
			(at 93.98 248.92 0)
			(effects
				(font
					(size 1.27 1.27)
					(thickness 0.15)
				)
				(justify left bottom)
				(hide yes)
			)
		)
		(property "Val" "1k"
			(at 76.2 231.775 0)
			(effects
				(font
					(size 1.27 1.27)
					(thickness 0.15)
				)
			)
		)
		(property "License" "Apache-2.0"
			(at 93.98 254 0)
			(effects
				(font
					(size 1.27 1.27)
					(thickness 0.15)
				)
				(justify left bottom)
				(hide yes)
			)
		)
		(property "Author" "Antmicro"
			(at 93.98 256.54 0)
			(effects
				(font
					(size 1.27 1.27)
					(thickness 0.15)
				)
				(justify left bottom)
				(hide yes)
			)
		)
		(property "Tolerance" "1%"
			(at 93.98 238.76 0)
			(effects
				(font
					(size 1.27 1.27)
				)
				(justify left bottom)
				(hide yes)
			)
		)
		(pin "1"
		)
		(pin "2"
		)
		(instances
			(project "artix-dc-scm"
				(path ""
					(reference "R129")
					(unit 1)
				)
			)
		)
	)
	(symbol
		(lib_id "antmicroResistors0402:R_4k7_0402")
		(at 92.71 72.39 270)
		(unit 1)
		(exclude_from_sim no)
		(in_bom yes)
		(on_board yes)
		(dnp no)
		(property "Reference" "R90"
			(at 93.98 73.66 90)
			(effects
				(font
					(size 1.27 1.27)
				)
				(justify left)
			)
		)
		(property "Value" "R_4k7_0402"
			(at 80.01 92.71 0)
			(effects
				(font
					(size 1.27 1.27)
					(thickness 0.15)
				)
				(justify left bottom)
				(hide yes)
			)
		)
		(property "Footprint" "antmicro-footprints:R_0402_1005Metric"
			(at 77.47 92.71 0)
			(effects
				(font
					(size 1.27 1.27)
					(thickness 0.15)
				)
				(justify left bottom)
				(hide yes)
			)
		)
		(property "Datasheet" "https://www.bourns.com/docs/product-datasheets/cr.pdf"
			(at 74.93 92.71 0)
			(effects
				(font
					(size 1.27 1.27)
					(thickness 0.15)
				)
				(justify left bottom)
				(hide yes)
			)
		)
		(property "Description" "SMD Chip Resistor, 4.7 kohm, ± 1%, 62.5 mW, 0402 [1005 Metric], Thick Film, General Purpose"
			(at 92.71 72.39 0)
			(effects
				(font
					(size 1.27 1.27)
				)
				(hide yes)
			)
		)
		(property "Manufacturer" "Bourns"
			(at 69.85 92.71 0)
			(effects
				(font
					(size 1.27 1.27)
					(thickness 0.15)
				)
				(justify left bottom)
				(hide yes)
			)
		)
		(property "MPN" "CR0402-FX-4701GLF"
			(at 72.39 92.71 0)
			(effects
				(font
					(size 1.27 1.27)
					(thickness 0.15)
				)
				(justify left bottom)
				(hide yes)
			)
		)
		(property "Val" "4k7"
			(at 93.98 76.2 90)
			(effects
				(font
					(size 1.27 1.27)
					(thickness 0.15)
				)
				(justify left)
			)
		)
		(property "License" "Apache-2.0"
			(at 67.31 92.71 0)
			(effects
				(font
					(size 1.27 1.27)
					(thickness 0.15)
				)
				(justify left bottom)
				(hide yes)
			)
		)
		(property "Author" "Antmicro"
			(at 64.77 92.71 0)
			(effects
				(font
					(size 1.27 1.27)
					(thickness 0.15)
				)
				(justify left bottom)
				(hide yes)
			)
		)
		(property "Tolerance" "1%"
			(at 82.55 92.71 0)
			(effects
				(font
					(size 1.27 1.27)
				)
				(justify left bottom)
				(hide yes)
			)
		)
		(pin "1"
		)
		(pin "2"
		)
		(instances
			(project "artix-dc-scm"
				(path ""
					(reference "R90")
					(unit 1)
				)
			)
		)
	)
	(symbol
		(lib_id "antmicroLEDIndicationDiscrete:LED_G_0603_LG_L29K-G2J1-24-Z")
		(at 59.69 196.85 0)
		(unit 1)
		(exclude_from_sim no)
		(in_bom yes)
		(on_board yes)
		(dnp no)
		(fields_autoplaced yes)
		(property "Reference" "D9"
			(at 62.23 186.69 0)
			(effects
				(font
					(size 1.27 1.27)
				)
			)
		)
		(property "Value" "LED_G_0603_LG_L29K-G2J1-24-Z"
			(at 82.55 204.47 0)
			(effects
				(font
					(size 1.27 1.27)
					(thickness 0.15)
				)
				(justify left bottom)
				(hide yes)
			)
		)
		(property "Footprint" "antmicro-footprints:LED_0603_1608Metric_G"
			(at 82.55 207.01 0)
			(effects
				(font
					(size 1.27 1.27)
					(thickness 0.15)
				)
				(justify left bottom)
				(hide yes)
			)
		)
		(property "Datasheet" "https://look.ams-osram.com/m/19ee86b3ae0ee95b/original/LG-L29K.pdf"
			(at 82.55 209.55 0)
			(effects
				(font
					(size 1.27 1.27)
					(thickness 0.15)
				)
				(justify left bottom)
				(hide yes)
			)
		)
		(property "Description" "LED, Green, SMD, 0603, 20 mA, 1.7 V, 570 nm"
			(at 59.69 196.85 0)
			(effects
				(font
					(size 1.27 1.27)
				)
				(hide yes)
			)
		)
		(property "MPN" "LG L29K-G2J1-24-Z"
			(at 62.23 189.23 0)
			(effects
				(font
					(size 1.27 1.27)
					(thickness 0.15)
				)
			)
		)
		(property "Manufacturer" "OSRAM"
			(at 82.55 214.63 0)
			(effects
				(font
					(size 1.27 1.27)
					(thickness 0.15)
				)
				(justify left bottom)
				(hide yes)
			)
		)
		(property "Author" "Antmicro"
			(at 82.55 217.17 0)
			(effects
				(font
					(size 1.27 1.27)
					(thickness 0.15)
				)
				(justify left bottom)
				(hide yes)
			)
		)
		(property "License" "Apache-2.0"
			(at 82.55 219.71 0)
			(effects
				(font
					(size 1.27 1.27)
					(thickness 0.15)
				)
				(justify left bottom)
				(hide yes)
			)
		)
		(property "Color" "Green"
			(at 62.23 191.77 0)
			(effects
				(font
					(size 1.27 1.27)
				)
			)
		)
		(pin "1"
		)
		(pin "2"
		)
		(instances
			(project "artix-dc-scm"
				(path ""
					(reference "D9")
					(unit 1)
				)
			)
		)
	)
	(symbol
		(lib_id "antmicroLEDIndicationDiscrete:LED_G_0603_LG_L29K-G2J1-24-Z")
		(at 154.94 260.35 0)
		(unit 1)
		(exclude_from_sim no)
		(in_bom yes)
		(on_board yes)
		(dnp no)
		(fields_autoplaced yes)
		(property "Reference" "D13"
			(at 157.48 250.19 0)
			(effects
				(font
					(size 1.27 1.27)
				)
			)
		)
		(property "Value" "LED_G_0603_LG_L29K-G2J1-24-Z"
			(at 158.75 255.27 0)
			(effects
				(font
					(size 1.27 1.27)
					(thickness 0.15)
				)
				(hide yes)
			)
		)
		(property "Footprint" "antmicro-footprints:LED_0603_1608Metric_G"
			(at 177.8 270.51 0)
			(effects
				(font
					(size 1.27 1.27)
					(thickness 0.15)
				)
				(justify left bottom)
				(hide yes)
			)
		)
		(property "Datasheet" "https://look.ams-osram.com/m/19ee86b3ae0ee95b/original/LG-L29K.pdf"
			(at 177.8 273.05 0)
			(effects
				(font
					(size 1.27 1.27)
					(thickness 0.15)
				)
				(justify left bottom)
				(hide yes)
			)
		)
		(property "Description" "LED, Green, SMD, 0603, 20 mA, 1.7 V, 570 nm"
			(at 154.94 260.35 0)
			(effects
				(font
					(size 1.27 1.27)
				)
				(hide yes)
			)
		)
		(property "MPN" "LG L29K-G2J1-24-Z"
			(at 157.48 252.73 0)
			(effects
				(font
					(size 1.27 1.27)
					(thickness 0.15)
				)
			)
		)
		(property "Manufacturer" "OSRAM"
			(at 177.8 278.13 0)
			(effects
				(font
					(size 1.27 1.27)
					(thickness 0.15)
				)
				(justify left bottom)
				(hide yes)
			)
		)
		(property "Author" "Antmicro"
			(at 177.8 280.67 0)
			(effects
				(font
					(size 1.27 1.27)
					(thickness 0.15)
				)
				(justify left bottom)
				(hide yes)
			)
		)
		(property "License" "Apache-2.0"
			(at 177.8 283.21 0)
			(effects
				(font
					(size 1.27 1.27)
					(thickness 0.15)
				)
				(justify left bottom)
				(hide yes)
			)
		)
		(property "Color" "Green"
			(at 157.48 255.27 0)
			(effects
				(font
					(size 1.27 1.27)
				)
			)
		)
		(pin "1"
		)
		(pin "2"
		)
		(instances
			(project "artix-dc-scm"
				(path ""
					(reference "D13")
					(unit 1)
				)
			)
		)
	)
	(symbol
		(lib_id "antmicropower:GND")
		(at 50.8 210.82 0)
		(unit 1)
		(exclude_from_sim no)
		(in_bom yes)
		(on_board yes)
		(dnp no)
		(property "Reference" "#PWR0323"
			(at 50.8 217.17 0)
			(effects
				(font
					(size 1.27 1.27)
				)
				(hide yes)
			)
		)
		(property "Value" "GND"
			(at 50.8 214.63 0)
			(effects
				(font
					(size 1.27 1.27)
				)
			)
		)
		(property "Footprint" ""
			(at 50.8 210.82 0)
			(effects
				(font
					(size 1.27 1.27)
				)
				(hide yes)
			)
		)
		(property "Datasheet" ""
			(at 50.8 210.82 0)
			(effects
				(font
					(size 1.27 1.27)
				)
				(hide yes)
			)
		)
		(property "Description" ""
			(at 50.8 210.82 0)
			(effects
				(font
					(size 1.27 1.27)
				)
				(hide yes)
			)
		)
		(property "Author" "Antmicro"
			(at 59.69 218.44 0)
			(effects
				(font
					(size 1.27 1.27)
					(thickness 0.15)
				)
				(justify left bottom)
				(hide yes)
			)
		)
		(property "License" "Apache-2.0"
			(at 59.69 220.98 0)
			(effects
				(font
					(size 1.27 1.27)
					(thickness 0.15)
				)
				(justify left bottom)
				(hide yes)
			)
		)
		(pin "1"
		)
		(instances
			(project "artix-dc-scm"
				(path ""
					(reference "#PWR0323")
					(unit 1)
				)
			)
		)
	)
	(symbol
		(lib_id "antmicropower:GND")
		(at 118.11 115.57 0)
		(unit 1)
		(exclude_from_sim no)
		(in_bom yes)
		(on_board yes)
		(dnp no)
		(property "Reference" "#PWR086"
			(at 118.11 121.92 0)
			(effects
				(font
					(size 1.27 1.27)
				)
				(hide yes)
			)
		)
		(property "Value" "GND"
			(at 118.11 119.38 0)
			(effects
				(font
					(size 1.27 1.27)
				)
			)
		)
		(property "Footprint" ""
			(at 118.11 115.57 0)
			(effects
				(font
					(size 1.27 1.27)
				)
				(hide yes)
			)
		)
		(property "Datasheet" ""
			(at 118.11 115.57 0)
			(effects
				(font
					(size 1.27 1.27)
				)
				(hide yes)
			)
		)
		(property "Description" ""
			(at 118.11 115.57 0)
			(effects
				(font
					(size 1.27 1.27)
				)
				(hide yes)
			)
		)
		(property "Author" "Antmicro"
			(at 127 123.19 0)
			(effects
				(font
					(size 1.27 1.27)
					(thickness 0.15)
				)
				(justify left bottom)
				(hide yes)
			)
		)
		(property "License" "Apache-2.0"
			(at 127 125.73 0)
			(effects
				(font
					(size 1.27 1.27)
					(thickness 0.15)
				)
				(justify left bottom)
				(hide yes)
			)
		)
		(pin "1"
		)
		(instances
			(project "artix-dc-scm"
				(path ""
					(reference "#PWR086")
					(unit 1)
				)
			)
		)
	)
	(symbol
		(lib_id "antmicroCapacitors0402:C_470n_0402")
		(at 241.3 64.77 90)
		(unit 1)
		(exclude_from_sim no)
		(in_bom yes)
		(on_board yes)
		(dnp no)
		(property "Reference" "C127"
			(at 241.935 60.325 90)
			(effects
				(font
					(size 1.27 1.27)
				)
				(justify right)
			)
		)
		(property "Value" "C_470n_0402"
			(at 251.46 44.45 0)
			(effects
				(font
					(size 1.27 1.27)
					(thickness 0.15)
				)
				(justify left bottom)
				(hide yes)
			)
		)
		(property "Footprint" "antmicro-footprints:C_0402_1005Metric"
			(at 254 44.45 0)
			(effects
				(font
					(size 1.27 1.27)
					(thickness 0.15)
				)
				(justify left bottom)
				(hide yes)
			)
		)
		(property "Datasheet" "https://product.tdk.com/en/search/capacitor/ceramic/mlcc/info?part_no=C1005X5R1E474M050BB"
			(at 256.54 44.45 0)
			(effects
				(font
					(size 1.27 1.27)
					(thickness 0.15)
				)
				(justify left bottom)
				(hide yes)
			)
		)
		(property "Description" "SMD Multilayer Ceramic Capacitor, 0.47 µF, 25 V, 0402 [1005 Metric], ± 20%, X5R, C"
			(at 241.3 64.77 0)
			(effects
				(font
					(size 1.27 1.27)
				)
				(hide yes)
			)
		)
		(property "Manufacturer" "TDK"
			(at 261.62 44.45 0)
			(effects
				(font
					(size 1.27 1.27)
					(thickness 0.15)
				)
				(justify left bottom)
				(hide yes)
			)
		)
		(property "MPN" "C1005X5R1E474M050BB"
			(at 259.08 44.45 0)
			(effects
				(font
					(size 1.27 1.27)
					(thickness 0.15)
				)
				(justify left bottom)
				(hide yes)
			)
		)
		(property "Val" "470n"
			(at 241.935 64.135 90)
			(effects
				(font
					(size 1.27 1.27)
					(thickness 0.15)
				)
				(justify right)
			)
		)
		(property "License" "Apache-2.0"
			(at 264.16 44.45 0)
			(effects
				(font
					(size 1.27 1.27)
					(thickness 0.15)
				)
				(justify left bottom)
				(hide yes)
			)
		)
		(property "Author" "Antmicro"
			(at 266.7 44.45 0)
			(effects
				(font
					(size 1.27 1.27)
					(thickness 0.15)
				)
				(justify left bottom)
				(hide yes)
			)
		)
		(property "Voltage" ""
			(at 269.24 44.45 0)
			(effects
				(font
					(size 1.27 1.27)
				)
				(justify left bottom)
				(hide yes)
			)
		)
		(property "Dielectric" ""
			(at 271.78 44.45 0)
			(effects
				(font
					(size 1.27 1.27)
				)
				(justify left bottom)
				(hide yes)
			)
		)
		(pin "1"
		)
		(pin "2"
		)
		(instances
			(project "artix-dc-scm"
				(path ""
					(reference "C127")
					(unit 1)
				)
			)
		)
	)
	(symbol
		(lib_id "antmicroCapacitors0402:C_470n_0402")
		(at 349.25 63.5 270)
		(mirror x)
		(unit 1)
		(exclude_from_sim no)
		(in_bom yes)
		(on_board yes)
		(dnp no)
		(property "Reference" "C243"
			(at 348.615 59.055 90)
			(effects
				(font
					(size 1.27 1.27)
				)
				(justify right)
			)
		)
		(property "Value" "C_470n_0402"
			(at 339.09 43.18 0)
			(effects
				(font
					(size 1.27 1.27)
					(thickness 0.15)
				)
				(justify left bottom)
				(hide yes)
			)
		)
		(property "Footprint" "antmicro-footprints:C_0402_1005Metric"
			(at 336.55 43.18 0)
			(effects
				(font
					(size 1.27 1.27)
					(thickness 0.15)
				)
				(justify left bottom)
				(hide yes)
			)
		)
		(property "Datasheet" "https://product.tdk.com/en/search/capacitor/ceramic/mlcc/info?part_no=C1005X5R1E474M050BB"
			(at 334.01 43.18 0)
			(effects
				(font
					(size 1.27 1.27)
					(thickness 0.15)
				)
				(justify left bottom)
				(hide yes)
			)
		)
		(property "Description" "SMD Multilayer Ceramic Capacitor, 0.47 µF, 25 V, 0402 [1005 Metric], ± 20%, X5R, C"
			(at 349.25 63.5 0)
			(effects
				(font
					(size 1.27 1.27)
				)
				(hide yes)
			)
		)
		(property "Manufacturer" "TDK"
			(at 328.93 43.18 0)
			(effects
				(font
					(size 1.27 1.27)
					(thickness 0.15)
				)
				(justify left bottom)
				(hide yes)
			)
		)
		(property "MPN" "C1005X5R1E474M050BB"
			(at 331.47 43.18 0)
			(effects
				(font
					(size 1.27 1.27)
					(thickness 0.15)
				)
				(justify left bottom)
				(hide yes)
			)
		)
		(property "Val" "470n"
			(at 348.615 62.865 90)
			(effects
				(font
					(size 1.27 1.27)
					(thickness 0.15)
				)
				(justify right)
			)
		)
		(property "License" "Apache-2.0"
			(at 326.39 43.18 0)
			(effects
				(font
					(size 1.27 1.27)
					(thickness 0.15)
				)
				(justify left bottom)
				(hide yes)
			)
		)
		(property "Author" "Antmicro"
			(at 323.85 43.18 0)
			(effects
				(font
					(size 1.27 1.27)
					(thickness 0.15)
				)
				(justify left bottom)
				(hide yes)
			)
		)
		(property "Voltage" ""
			(at 321.31 43.18 0)
			(effects
				(font
					(size 1.27 1.27)
				)
				(justify left bottom)
				(hide yes)
			)
		)
		(property "Dielectric" ""
			(at 318.77 43.18 0)
			(effects
				(font
					(size 1.27 1.27)
				)
				(justify left bottom)
				(hide yes)
			)
		)
		(property "DNP" ""
			(at 349.25 63.5 0)
			(effects
				(font
					(size 1.27 1.27)
				)
			)
		)
		(pin "1"
		)
		(pin "2"
		)
		(instances
			(project "artix-dc-scm"
				(path ""
					(reference "C243")
					(unit 1)
				)
			)
		)
	)
	(symbol
		(lib_id "antmicroResistors0402:R_4k7_0402")
		(at 77.47 72.39 270)
		(unit 1)
		(exclude_from_sim no)
		(in_bom yes)
		(on_board yes)
		(dnp no)
		(property "Reference" "R85"
			(at 78.74 73.66 90)
			(effects
				(font
					(size 1.27 1.27)
				)
				(justify left)
			)
		)
		(property "Value" "R_4k7_0402"
			(at 64.77 92.71 0)
			(effects
				(font
					(size 1.27 1.27)
					(thickness 0.15)
				)
				(justify left bottom)
				(hide yes)
			)
		)
		(property "Footprint" "antmicro-footprints:R_0402_1005Metric"
			(at 62.23 92.71 0)
			(effects
				(font
					(size 1.27 1.27)
					(thickness 0.15)
				)
				(justify left bottom)
				(hide yes)
			)
		)
		(property "Datasheet" "https://www.bourns.com/docs/product-datasheets/cr.pdf"
			(at 59.69 92.71 0)
			(effects
				(font
					(size 1.27 1.27)
					(thickness 0.15)
				)
				(justify left bottom)
				(hide yes)
			)
		)
		(property "Description" "SMD Chip Resistor, 4.7 kohm, ± 1%, 62.5 mW, 0402 [1005 Metric], Thick Film, General Purpose"
			(at 77.47 72.39 0)
			(effects
				(font
					(size 1.27 1.27)
				)
				(hide yes)
			)
		)
		(property "Manufacturer" "Bourns"
			(at 54.61 92.71 0)
			(effects
				(font
					(size 1.27 1.27)
					(thickness 0.15)
				)
				(justify left bottom)
				(hide yes)
			)
		)
		(property "MPN" "CR0402-FX-4701GLF"
			(at 57.15 92.71 0)
			(effects
				(font
					(size 1.27 1.27)
					(thickness 0.15)
				)
				(justify left bottom)
				(hide yes)
			)
		)
		(property "Val" "4k7"
			(at 78.74 76.2 90)
			(effects
				(font
					(size 1.27 1.27)
					(thickness 0.15)
				)
				(justify left)
			)
		)
		(property "License" "Apache-2.0"
			(at 52.07 92.71 0)
			(effects
				(font
					(size 1.27 1.27)
					(thickness 0.15)
				)
				(justify left bottom)
				(hide yes)
			)
		)
		(property "Author" "Antmicro"
			(at 49.53 92.71 0)
			(effects
				(font
					(size 1.27 1.27)
					(thickness 0.15)
				)
				(justify left bottom)
				(hide yes)
			)
		)
		(property "Tolerance" "1%"
			(at 67.31 92.71 0)
			(effects
				(font
					(size 1.27 1.27)
				)
				(justify left bottom)
				(hide yes)
			)
		)
		(pin "1"
		)
		(pin "2"
		)
		(instances
			(project "artix-dc-scm"
				(path ""
					(reference "R85")
					(unit 1)
				)
			)
		)
	)
	(symbol
		(lib_id "antmicroTestPoints:TP_1mm_SMD")
		(at 86.36 88.9 270)
		(unit 1)
		(exclude_from_sim no)
		(in_bom no)
		(on_board yes)
		(dnp no)
		(property "Reference" "TP6"
			(at 84.455 93.98 90)
			(effects
				(font
					(size 1.27 1.27)
				)
				(justify left)
			)
		)
		(property "Value" "TP_1mm_SMD"
			(at 83.82 88.9 0)
			(effects
				(font
					(size 1.27 1.27)
				)
				(hide yes)
			)
		)
		(property "Footprint" "antmicro-footprints:TP_SMD_1mm"
			(at 76.2 104.14 0)
			(effects
				(font
					(size 1.27 1.27)
					(thickness 0.15)
				)
				(justify left bottom)
				(hide yes)
			)
		)
		(property "Datasheet" ""
			(at 73.66 104.14 0)
			(effects
				(font
					(size 1.27 1.27)
					(thickness 0.15)
				)
				(justify left bottom)
				(hide yes)
			)
		)
		(property "Description" "Test point 1mm SMD"
			(at 86.36 88.9 0)
			(effects
				(font
					(size 1.27 1.27)
				)
				(hide yes)
			)
		)
		(property "MPN" ""
			(at 86.36 88.9 0)
			(effects
				(font
					(size 1.27 1.27)
				)
				(hide yes)
			)
		)
		(property "Manufacturer" ""
			(at 86.36 88.9 0)
			(effects
				(font
					(size 1.27 1.27)
				)
				(hide yes)
			)
		)
		(property "Author" "Antmicro"
			(at 71.12 104.14 0)
			(effects
				(font
					(size 1.27 1.27)
					(thickness 0.15)
				)
				(justify left bottom)
				(hide yes)
			)
		)
		(property "License" "Apache-2.0"
			(at 68.58 104.14 0)
			(effects
				(font
					(size 1.27 1.27)
					(thickness 0.15)
				)
				(justify left bottom)
				(hide yes)
			)
		)
		(pin "1"
		)
		(instances
			(project "artix-dc-scm"
				(path ""
					(reference "TP6")
					(unit 1)
				)
			)
		)
	)
	(symbol
		(lib_id "antmicropower:GND")
		(at 259.08 64.77 0)
		(unit 1)
		(exclude_from_sim no)
		(in_bom yes)
		(on_board yes)
		(dnp no)
		(property "Reference" "#PWR0318"
			(at 259.08 71.12 0)
			(effects
				(font
					(size 1.27 1.27)
				)
				(hide yes)
			)
		)
		(property "Value" "GND"
			(at 259.08 68.58 0)
			(effects
				(font
					(size 1.27 1.27)
				)
			)
		)
		(property "Footprint" ""
			(at 259.08 64.77 0)
			(effects
				(font
					(size 1.27 1.27)
				)
				(hide yes)
			)
		)
		(property "Datasheet" ""
			(at 259.08 64.77 0)
			(effects
				(font
					(size 1.27 1.27)
				)
				(hide yes)
			)
		)
		(property "Description" ""
			(at 259.08 64.77 0)
			(effects
				(font
					(size 1.27 1.27)
				)
				(hide yes)
			)
		)
		(property "Author" "Antmicro"
			(at 267.97 72.39 0)
			(effects
				(font
					(size 1.27 1.27)
					(thickness 0.15)
				)
				(justify left bottom)
				(hide yes)
			)
		)
		(property "License" "Apache-2.0"
			(at 267.97 74.93 0)
			(effects
				(font
					(size 1.27 1.27)
					(thickness 0.15)
				)
				(justify left bottom)
				(hide yes)
			)
		)
		(pin "1"
		)
		(instances
			(project "artix-dc-scm"
				(path ""
					(reference "#PWR0318")
					(unit 1)
				)
			)
		)
	)
	(symbol
		(lib_id "antmicropower:GND")
		(at 232.41 64.77 0)
		(unit 1)
		(exclude_from_sim no)
		(in_bom yes)
		(on_board yes)
		(dnp no)
		(property "Reference" "#PWR0321"
			(at 232.41 71.12 0)
			(effects
				(font
					(size 1.27 1.27)
				)
				(hide yes)
			)
		)
		(property "Value" "GND"
			(at 232.41 68.58 0)
			(effects
				(font
					(size 1.27 1.27)
				)
			)
		)
		(property "Footprint" ""
			(at 232.41 64.77 0)
			(effects
				(font
					(size 1.27 1.27)
				)
				(hide yes)
			)
		)
		(property "Datasheet" ""
			(at 232.41 64.77 0)
			(effects
				(font
					(size 1.27 1.27)
				)
				(hide yes)
			)
		)
		(property "Description" ""
			(at 232.41 64.77 0)
			(effects
				(font
					(size 1.27 1.27)
				)
				(hide yes)
			)
		)
		(property "Author" "Antmicro"
			(at 241.3 72.39 0)
			(effects
				(font
					(size 1.27 1.27)
					(thickness 0.15)
				)
				(justify left bottom)
				(hide yes)
			)
		)
		(property "License" "Apache-2.0"
			(at 241.3 74.93 0)
			(effects
				(font
					(size 1.27 1.27)
					(thickness 0.15)
				)
				(justify left bottom)
				(hide yes)
			)
		)
		(pin "1"
		)
		(instances
			(project "artix-dc-scm"
				(path ""
					(reference "#PWR0321")
					(unit 1)
				)
			)
		)
	)
	(symbol
		(lib_id "antmicropower:GND")
		(at 349.25 63.5 0)
		(mirror y)
		(unit 1)
		(exclude_from_sim no)
		(in_bom yes)
		(on_board yes)
		(dnp no)
		(property "Reference" "#PWR053"
			(at 349.25 69.85 0)
			(effects
				(font
					(size 1.27 1.27)
				)
				(hide yes)
			)
		)
		(property "Value" "GND"
			(at 349.25 67.31 0)
			(effects
				(font
					(size 1.27 1.27)
				)
			)
		)
		(property "Footprint" ""
			(at 349.25 63.5 0)
			(effects
				(font
					(size 1.27 1.27)
				)
				(hide yes)
			)
		)
		(property "Datasheet" ""
			(at 349.25 63.5 0)
			(effects
				(font
					(size 1.27 1.27)
				)
				(hide yes)
			)
		)
		(property "Description" ""
			(at 349.25 63.5 0)
			(effects
				(font
					(size 1.27 1.27)
				)
				(hide yes)
			)
		)
		(property "Author" "Antmicro"
			(at 340.36 71.12 0)
			(effects
				(font
					(size 1.27 1.27)
					(thickness 0.15)
				)
				(justify left bottom)
				(hide yes)
			)
		)
		(property "License" "Apache-2.0"
			(at 340.36 73.66 0)
			(effects
				(font
					(size 1.27 1.27)
					(thickness 0.15)
				)
				(justify left bottom)
				(hide yes)
			)
		)
		(pin "1"
		)
		(instances
			(project "artix-dc-scm"
				(path ""
					(reference "#PWR053")
					(unit 1)
				)
			)
		)
	)
	(symbol
		(lib_id "antmicroCapacitorsmisc:C_47u_1210")
		(at 232.41 50.8 90)
		(unit 1)
		(exclude_from_sim no)
		(in_bom yes)
		(on_board yes)
		(dnp no)
		(property "Reference" "C91"
			(at 233.045 46.355 90)
			(effects
				(font
					(size 1.27 1.27)
				)
				(justify right)
			)
		)
		(property "Value" "C_47u_1210"
			(at 242.57 30.48 0)
			(effects
				(font
					(size 1.27 1.27)
					(thickness 0.15)
				)
				(justify left bottom)
				(hide yes)
			)
		)
		(property "Footprint" "antmicro-footprints:C_1210_3225Metric"
			(at 245.11 30.48 0)
			(effects
				(font
					(size 1.27 1.27)
					(thickness 0.15)
				)
				(justify left bottom)
				(hide yes)
			)
		)
		(property "Datasheet" "https://www.kemet.com/en/us/capacitors/product/C1210C476K8RACTU.html"
			(at 247.65 30.48 0)
			(effects
				(font
					(size 1.27 1.27)
					(thickness 0.15)
				)
				(justify left bottom)
				(hide yes)
			)
		)
		(property "Description" "SMD Multilayer Ceramic Capacitor, 47 µF, 10 V, 1210 [3225 Metric], ± 10%, X7R, C Series KEMET"
			(at 232.41 50.8 0)
			(effects
				(font
					(size 1.27 1.27)
				)
				(hide yes)
			)
		)
		(property "Manufacturer" "KEMET"
			(at 252.73 30.48 0)
			(effects
				(font
					(size 1.27 1.27)
					(thickness 0.15)
				)
				(justify left bottom)
				(hide yes)
			)
		)
		(property "MPN" "C1210C476K8RACTU"
			(at 250.19 30.48 0)
			(effects
				(font
					(size 1.27 1.27)
					(thickness 0.15)
				)
				(justify left bottom)
				(hide yes)
			)
		)
		(property "Val" "47u"
			(at 233.045 50.165 90)
			(effects
				(font
					(size 1.27 1.27)
					(thickness 0.15)
				)
				(justify right)
			)
		)
		(property "License" "Apache-2.0"
			(at 255.27 30.48 0)
			(effects
				(font
					(size 1.27 1.27)
					(thickness 0.15)
				)
				(justify left bottom)
				(hide yes)
			)
		)
		(property "Author" "Antmicro"
			(at 257.81 30.48 0)
			(effects
				(font
					(size 1.27 1.27)
					(thickness 0.15)
				)
				(justify left bottom)
				(hide yes)
			)
		)
		(property "Voltage" ""
			(at 260.35 30.48 0)
			(effects
				(font
					(size 1.27 1.27)
				)
				(justify left bottom)
				(hide yes)
			)
		)
		(property "Dielectric" ""
			(at 262.89 30.48 0)
			(effects
				(font
					(size 1.27 1.27)
				)
				(justify left bottom)
				(hide yes)
			)
		)
		(property "Public" "False"
			(at 265.43 30.48 0)
			(effects
				(font
					(size 1.27 1.27)
				)
				(justify left bottom)
				(hide yes)
			)
		)
		(pin "1"
		)
		(pin "2"
		)
		(instances
			(project "artix-dc-scm"
				(path ""
					(reference "C91")
					(unit 1)
				)
			)
		)
	)
	(symbol
		(lib_id "antmicropower:GND")
		(at 50.8 242.57 0)
		(unit 1)
		(exclude_from_sim no)
		(in_bom yes)
		(on_board yes)
		(dnp no)
		(property "Reference" "#PWR0326"
			(at 50.8 248.92 0)
			(effects
				(font
					(size 1.27 1.27)
				)
				(hide yes)
			)
		)
		(property "Value" "GND"
			(at 50.8 246.38 0)
			(effects
				(font
					(size 1.27 1.27)
				)
			)
		)
		(property "Footprint" ""
			(at 50.8 242.57 0)
			(effects
				(font
					(size 1.27 1.27)
				)
				(hide yes)
			)
		)
		(property "Datasheet" ""
			(at 50.8 242.57 0)
			(effects
				(font
					(size 1.27 1.27)
				)
				(hide yes)
			)
		)
		(property "Description" ""
			(at 50.8 242.57 0)
			(effects
				(font
					(size 1.27 1.27)
				)
				(hide yes)
			)
		)
		(property "Author" "Antmicro"
			(at 59.69 250.19 0)
			(effects
				(font
					(size 1.27 1.27)
					(thickness 0.15)
				)
				(justify left bottom)
				(hide yes)
			)
		)
		(property "License" "Apache-2.0"
			(at 59.69 252.73 0)
			(effects
				(font
					(size 1.27 1.27)
					(thickness 0.15)
				)
				(justify left bottom)
				(hide yes)
			)
		)
		(pin "1"
		)
		(instances
			(project "artix-dc-scm"
				(path ""
					(reference "#PWR0326")
					(unit 1)
				)
			)
		)
	)
	(symbol
		(lib_id "antmicropower:GND")
		(at 123.19 151.13 0)
		(unit 1)
		(exclude_from_sim no)
		(in_bom yes)
		(on_board yes)
		(dnp no)
		(property "Reference" "#PWR0322"
			(at 123.19 157.48 0)
			(effects
				(font
					(size 1.27 1.27)
				)
				(hide yes)
			)
		)
		(property "Value" "GND"
			(at 123.19 154.94 0)
			(effects
				(font
					(size 1.27 1.27)
				)
			)
		)
		(property "Footprint" ""
			(at 123.19 151.13 0)
			(effects
				(font
					(size 1.27 1.27)
				)
				(hide yes)
			)
		)
		(property "Datasheet" ""
			(at 123.19 151.13 0)
			(effects
				(font
					(size 1.27 1.27)
				)
				(hide yes)
			)
		)
		(property "Description" ""
			(at 123.19 151.13 0)
			(effects
				(font
					(size 1.27 1.27)
				)
				(hide yes)
			)
		)
		(property "Author" "Antmicro"
			(at 132.08 158.75 0)
			(effects
				(font
					(size 1.27 1.27)
					(thickness 0.15)
				)
				(justify left bottom)
				(hide yes)
			)
		)
		(property "License" "Apache-2.0"
			(at 132.08 161.29 0)
			(effects
				(font
					(size 1.27 1.27)
					(thickness 0.15)
				)
				(justify left bottom)
				(hide yes)
			)
		)
		(pin "1"
		)
		(instances
			(project "artix-dc-scm"
				(path ""
					(reference "#PWR0322")
					(unit 1)
				)
			)
		)
	)
	(symbol
		(lib_id "antmicroCapacitors0402:C_470n_0402")
		(at 259.08 64.77 90)
		(unit 1)
		(exclude_from_sim no)
		(in_bom yes)
		(on_board yes)
		(dnp no)
		(property "Reference" "C239"
			(at 259.715 60.325 90)
			(effects
				(font
					(size 1.27 1.27)
				)
				(justify right)
			)
		)
		(property "Value" "C_470n_0402"
			(at 269.24 44.45 0)
			(effects
				(font
					(size 1.27 1.27)
					(thickness 0.15)
				)
				(justify left bottom)
				(hide yes)
			)
		)
		(property "Footprint" "antmicro-footprints:C_0402_1005Metric"
			(at 271.78 44.45 0)
			(effects
				(font
					(size 1.27 1.27)
					(thickness 0.15)
				)
				(justify left bottom)
				(hide yes)
			)
		)
		(property "Datasheet" "https://product.tdk.com/en/search/capacitor/ceramic/mlcc/info?part_no=C1005X5R1E474M050BB"
			(at 274.32 44.45 0)
			(effects
				(font
					(size 1.27 1.27)
					(thickness 0.15)
				)
				(justify left bottom)
				(hide yes)
			)
		)
		(property "Description" "SMD Multilayer Ceramic Capacitor, 0.47 µF, 25 V, 0402 [1005 Metric], ± 20%, X5R, C"
			(at 259.08 64.77 0)
			(effects
				(font
					(size 1.27 1.27)
				)
				(hide yes)
			)
		)
		(property "Manufacturer" "TDK"
			(at 279.4 44.45 0)
			(effects
				(font
					(size 1.27 1.27)
					(thickness 0.15)
				)
				(justify left bottom)
				(hide yes)
			)
		)
		(property "MPN" "C1005X5R1E474M050BB"
			(at 276.86 44.45 0)
			(effects
				(font
					(size 1.27 1.27)
					(thickness 0.15)
				)
				(justify left bottom)
				(hide yes)
			)
		)
		(property "Val" "470n"
			(at 259.715 64.135 90)
			(effects
				(font
					(size 1.27 1.27)
					(thickness 0.15)
				)
				(justify right)
			)
		)
		(property "License" "Apache-2.0"
			(at 281.94 44.45 0)
			(effects
				(font
					(size 1.27 1.27)
					(thickness 0.15)
				)
				(justify left bottom)
				(hide yes)
			)
		)
		(property "Author" "Antmicro"
			(at 284.48 44.45 0)
			(effects
				(font
					(size 1.27 1.27)
					(thickness 0.15)
				)
				(justify left bottom)
				(hide yes)
			)
		)
		(property "Voltage" ""
			(at 287.02 44.45 0)
			(effects
				(font
					(size 1.27 1.27)
				)
				(justify left bottom)
				(hide yes)
			)
		)
		(property "Dielectric" ""
			(at 289.56 44.45 0)
			(effects
				(font
					(size 1.27 1.27)
				)
				(justify left bottom)
				(hide yes)
			)
		)
		(pin "1"
		)
		(pin "2"
		)
		(instances
			(project "artix-dc-scm"
				(path ""
					(reference "C239")
					(unit 1)
				)
			)
		)
	)
	(symbol
		(lib_id "antmicropower:GND")
		(at 241.3 64.77 0)
		(unit 1)
		(exclude_from_sim no)
		(in_bom yes)
		(on_board yes)
		(dnp no)
		(property "Reference" "#PWR0320"
			(at 241.3 71.12 0)
			(effects
				(font
					(size 1.27 1.27)
				)
				(hide yes)
			)
		)
		(property "Value" "GND"
			(at 241.3 68.58 0)
			(effects
				(font
					(size 1.27 1.27)
				)
			)
		)
		(property "Footprint" ""
			(at 241.3 64.77 0)
			(effects
				(font
					(size 1.27 1.27)
				)
				(hide yes)
			)
		)
		(property "Datasheet" ""
			(at 241.3 64.77 0)
			(effects
				(font
					(size 1.27 1.27)
				)
				(hide yes)
			)
		)
		(property "Description" ""
			(at 241.3 64.77 0)
			(effects
				(font
					(size 1.27 1.27)
				)
				(hide yes)
			)
		)
		(property "Author" "Antmicro"
			(at 250.19 72.39 0)
			(effects
				(font
					(size 1.27 1.27)
					(thickness 0.15)
				)
				(justify left bottom)
				(hide yes)
			)
		)
		(property "License" "Apache-2.0"
			(at 250.19 74.93 0)
			(effects
				(font
					(size 1.27 1.27)
					(thickness 0.15)
				)
				(justify left bottom)
				(hide yes)
			)
		)
		(pin "1"
		)
		(instances
			(project "artix-dc-scm"
				(path ""
					(reference "#PWR0320")
					(unit 1)
				)
			)
		)
	)
	(symbol
		(lib_id "antmicropower:GND")
		(at 259.08 50.8 0)
		(unit 1)
		(exclude_from_sim no)
		(in_bom yes)
		(on_board yes)
		(dnp no)
		(property "Reference" "#PWR0314"
			(at 259.08 57.15 0)
			(effects
				(font
					(size 1.27 1.27)
				)
				(hide yes)
			)
		)
		(property "Value" "GND"
			(at 259.08 54.61 0)
			(effects
				(font
					(size 1.27 1.27)
				)
			)
		)
		(property "Footprint" ""
			(at 259.08 50.8 0)
			(effects
				(font
					(size 1.27 1.27)
				)
				(hide yes)
			)
		)
		(property "Datasheet" ""
			(at 259.08 50.8 0)
			(effects
				(font
					(size 1.27 1.27)
				)
				(hide yes)
			)
		)
		(property "Description" ""
			(at 259.08 50.8 0)
			(effects
				(font
					(size 1.27 1.27)
				)
				(hide yes)
			)
		)
		(property "Author" "Antmicro"
			(at 267.97 58.42 0)
			(effects
				(font
					(size 1.27 1.27)
					(thickness 0.15)
				)
				(justify left bottom)
				(hide yes)
			)
		)
		(property "License" "Apache-2.0"
			(at 267.97 60.96 0)
			(effects
				(font
					(size 1.27 1.27)
					(thickness 0.15)
				)
				(justify left bottom)
				(hide yes)
			)
		)
		(pin "1"
		)
		(instances
			(project "artix-dc-scm"
				(path ""
					(reference "#PWR0314")
					(unit 1)
				)
			)
		)
	)
	(symbol
		(lib_id "antmicroCapacitors0402:C_470n_0402")
		(at 365.76 63.5 270)
		(mirror x)
		(unit 1)
		(exclude_from_sim no)
		(in_bom yes)
		(on_board yes)
		(dnp no)
		(property "Reference" "C126"
			(at 364.49 59.055 90)
			(effects
				(font
					(size 1.27 1.27)
				)
				(justify right)
			)
		)
		(property "Value" "C_470n_0402"
			(at 355.6 43.18 0)
			(effects
				(font
					(size 1.27 1.27)
					(thickness 0.15)
				)
				(justify left bottom)
				(hide yes)
			)
		)
		(property "Footprint" "antmicro-footprints:C_0402_1005Metric"
			(at 353.06 43.18 0)
			(effects
				(font
					(size 1.27 1.27)
					(thickness 0.15)
				)
				(justify left bottom)
				(hide yes)
			)
		)
		(property "Datasheet" "https://product.tdk.com/en/search/capacitor/ceramic/mlcc/info?part_no=C1005X5R1E474M050BB"
			(at 350.52 43.18 0)
			(effects
				(font
					(size 1.27 1.27)
					(thickness 0.15)
				)
				(justify left bottom)
				(hide yes)
			)
		)
		(property "Description" "SMD Multilayer Ceramic Capacitor, 0.47 µF, 25 V, 0402 [1005 Metric], ± 20%, X5R, C"
			(at 365.76 63.5 0)
			(effects
				(font
					(size 1.27 1.27)
				)
				(hide yes)
			)
		)
		(property "Manufacturer" "TDK"
			(at 345.44 43.18 0)
			(effects
				(font
					(size 1.27 1.27)
					(thickness 0.15)
				)
				(justify left bottom)
				(hide yes)
			)
		)
		(property "MPN" "C1005X5R1E474M050BB"
			(at 347.98 43.18 0)
			(effects
				(font
					(size 1.27 1.27)
					(thickness 0.15)
				)
				(justify left bottom)
				(hide yes)
			)
		)
		(property "Val" "470n"
			(at 365.125 62.865 90)
			(effects
				(font
					(size 1.27 1.27)
					(thickness 0.15)
				)
				(justify right)
			)
		)
		(property "License" "Apache-2.0"
			(at 342.9 43.18 0)
			(effects
				(font
					(size 1.27 1.27)
					(thickness 0.15)
				)
				(justify left bottom)
				(hide yes)
			)
		)
		(property "Author" "Antmicro"
			(at 340.36 43.18 0)
			(effects
				(font
					(size 1.27 1.27)
					(thickness 0.15)
				)
				(justify left bottom)
				(hide yes)
			)
		)
		(property "Voltage" ""
			(at 337.82 43.18 0)
			(effects
				(font
					(size 1.27 1.27)
				)
				(justify left bottom)
				(hide yes)
			)
		)
		(property "Dielectric" ""
			(at 335.28 43.18 0)
			(effects
				(font
					(size 1.27 1.27)
				)
				(justify left bottom)
				(hide yes)
			)
		)
		(property "DNP" ""
			(at 365.76 63.5 0)
			(effects
				(font
					(size 1.27 1.27)
				)
			)
		)
		(pin "1"
		)
		(pin "2"
		)
		(instances
			(project "artix-dc-scm"
				(path ""
					(reference "C126")
					(unit 1)
				)
			)
		)
	)
	(symbol
		(lib_id "antmicroTransistorsFETsMOSFETsSingle:2N7002_SOT-23-3")
		(at 43.18 238.76 0)
		(unit 1)
		(exclude_from_sim no)
		(in_bom yes)
		(on_board yes)
		(dnp no)
		(fields_autoplaced yes)
		(property "Reference" "Q13"
			(at 54.61 234.9499 0)
			(effects
				(font
					(size 1.27 1.27)
				)
				(justify left)
			)
		)
		(property "Value" "2N7002_SOT-23-3"
			(at 54.61 237.4899 0)
			(effects
				(font
					(size 1.27 1.27)
					(thickness 0.15)
				)
				(justify left)
				(hide yes)
			)
		)
		(property "Footprint" "antmicro-footprints:SOT-23-3"
			(at 66.04 248.92 0)
			(effects
				(font
					(size 1.27 1.27)
					(thickness 0.15)
				)
				(justify left bottom)
				(hide yes)
			)
		)
		(property "Datasheet" "https://www.onsemi.com/pub/Collateral/NDS7002A-D.PDF"
			(at 66.04 251.46 0)
			(effects
				(font
					(size 1.27 1.27)
					(thickness 0.15)
				)
				(justify left bottom)
				(hide yes)
			)
		)
		(property "Description" "Power MOSFET, N Channel, 60 V, 115 mA, 1.2 ohm, SOT-23, Surface Mount"
			(at 43.18 238.76 0)
			(effects
				(font
					(size 1.27 1.27)
				)
				(hide yes)
			)
		)
		(property "MPN" "2N7002"
			(at 54.61 237.4899 0)
			(effects
				(font
					(size 1.27 1.27)
					(thickness 0.15)
				)
				(justify left)
			)
		)
		(property "Manufacturer" "ON Semiconductor"
			(at 66.04 256.54 0)
			(effects
				(font
					(size 1.27 1.27)
					(thickness 0.15)
				)
				(justify left bottom)
				(hide yes)
			)
		)
		(property "Author" "Antmicro"
			(at 66.04 259.08 0)
			(effects
				(font
					(size 1.27 1.27)
					(thickness 0.15)
				)
				(justify left bottom)
				(hide yes)
			)
		)
		(property "License" "Apache-2.0"
			(at 66.04 261.62 0)
			(effects
				(font
					(size 1.27 1.27)
					(thickness 0.15)
				)
				(justify left bottom)
				(hide yes)
			)
		)
		(pin "1"
		)
		(pin "2"
		)
		(pin "3"
		)
		(instances
			(project "artix-dc-scm"
				(path ""
					(reference "Q13")
					(unit 1)
				)
			)
		)
	)
	(symbol
		(lib_id "antmicroResistors0402:R_0R_0402")
		(at 123.19 151.13 90)
		(unit 1)
		(exclude_from_sim no)
		(in_bom yes)
		(on_board yes)
		(dnp no)
		(property "Reference" "R84"
			(at 124.46 147.32 90)
			(effects
				(font
					(size 1.27 1.27)
				)
				(justify right)
			)
		)
		(property "Value" "R_0R_0402"
			(at 135.89 130.81 0)
			(effects
				(font
					(size 1.27 1.27)
					(thickness 0.15)
				)
				(justify left bottom)
				(hide yes)
			)
		)
		(property "Footprint" "antmicro-footprints:R_0402_1005Metric"
			(at 138.43 130.81 0)
			(effects
				(font
					(size 1.27 1.27)
					(thickness 0.15)
				)
				(justify left bottom)
				(hide yes)
			)
		)
		(property "Datasheet" "https://industrial.panasonic.com/cdbs/www-data/pdf/RDA0000/AOA0000C301.pdf"
			(at 140.97 130.81 0)
			(effects
				(font
					(size 1.27 1.27)
					(thickness 0.15)
				)
				(justify left bottom)
				(hide yes)
			)
		)
		(property "Description" "SMD Chip Resistor, Jumper, 0 ohm, 100 mW, 0402 [1005 Metric], Thick Film, General Purpose"
			(at 123.19 151.13 0)
			(effects
				(font
					(size 1.27 1.27)
				)
				(hide yes)
			)
		)
		(property "Manufacturer" "Panasonic"
			(at 146.05 130.81 0)
			(effects
				(font
					(size 1.27 1.27)
					(thickness 0.15)
				)
				(justify left bottom)
				(hide yes)
			)
		)
		(property "MPN" "ERJ2GE0R00X"
			(at 143.51 130.81 0)
			(effects
				(font
					(size 1.27 1.27)
					(thickness 0.15)
				)
				(justify left bottom)
				(hide yes)
			)
		)
		(property "Val" "0R"
			(at 124.46 149.86 90)
			(effects
				(font
					(size 1.27 1.27)
					(thickness 0.15)
				)
				(justify right)
			)
		)
		(property "License" "Apache-2.0"
			(at 148.59 130.81 0)
			(effects
				(font
					(size 1.27 1.27)
					(thickness 0.15)
				)
				(justify left bottom)
				(hide yes)
			)
		)
		(property "Author" "Antmicro"
			(at 151.13 130.81 0)
			(effects
				(font
					(size 1.27 1.27)
					(thickness 0.15)
				)
				(justify left bottom)
				(hide yes)
			)
		)
		(property "Tolerance" "~"
			(at 133.35 130.81 0)
			(effects
				(font
					(size 1.27 1.27)
				)
				(justify left bottom)
				(hide yes)
			)
		)
		(property "Current" "1A"
			(at 153.67 130.81 0)
			(effects
				(font
					(size 1.27 1.27)
					(thickness 0.15)
				)
				(justify left bottom)
				(hide yes)
			)
		)
		(property "DNP" ""
			(at 123.19 148.59 0)
			(effects
				(font
					(size 1.27 1.27)
				)
			)
		)
		(pin "1"
		)
		(pin "2"
		)
		(instances
			(project "artix-dc-scm"
				(path ""
					(reference "R84")
					(unit 1)
				)
			)
		)
	)
	(symbol
		(lib_id "antmicroCapacitors0402:C_470n_0402")
		(at 340.36 63.5 270)
		(mirror x)
		(unit 1)
		(exclude_from_sim no)
		(in_bom yes)
		(on_board yes)
		(dnp no)
		(property "Reference" "C244"
			(at 339.725 59.055 90)
			(effects
				(font
					(size 1.27 1.27)
				)
				(justify right)
			)
		)
		(property "Value" "C_470n_0402"
			(at 330.2 43.18 0)
			(effects
				(font
					(size 1.27 1.27)
					(thickness 0.15)
				)
				(justify left bottom)
				(hide yes)
			)
		)
		(property "Footprint" "antmicro-footprints:C_0402_1005Metric"
			(at 327.66 43.18 0)
			(effects
				(font
					(size 1.27 1.27)
					(thickness 0.15)
				)
				(justify left bottom)
				(hide yes)
			)
		)
		(property "Datasheet" "https://product.tdk.com/en/search/capacitor/ceramic/mlcc/info?part_no=C1005X5R1E474M050BB"
			(at 325.12 43.18 0)
			(effects
				(font
					(size 1.27 1.27)
					(thickness 0.15)
				)
				(justify left bottom)
				(hide yes)
			)
		)
		(property "Description" "SMD Multilayer Ceramic Capacitor, 0.47 µF, 25 V, 0402 [1005 Metric], ± 20%, X5R, C"
			(at 340.36 63.5 0)
			(effects
				(font
					(size 1.27 1.27)
				)
				(hide yes)
			)
		)
		(property "Manufacturer" "TDK"
			(at 320.04 43.18 0)
			(effects
				(font
					(size 1.27 1.27)
					(thickness 0.15)
				)
				(justify left bottom)
				(hide yes)
			)
		)
		(property "MPN" "C1005X5R1E474M050BB"
			(at 322.58 43.18 0)
			(effects
				(font
					(size 1.27 1.27)
					(thickness 0.15)
				)
				(justify left bottom)
				(hide yes)
			)
		)
		(property "Val" "470n"
			(at 339.725 62.865 90)
			(effects
				(font
					(size 1.27 1.27)
					(thickness 0.15)
				)
				(justify right)
			)
		)
		(property "License" "Apache-2.0"
			(at 317.5 43.18 0)
			(effects
				(font
					(size 1.27 1.27)
					(thickness 0.15)
				)
				(justify left bottom)
				(hide yes)
			)
		)
		(property "Author" "Antmicro"
			(at 314.96 43.18 0)
			(effects
				(font
					(size 1.27 1.27)
					(thickness 0.15)
				)
				(justify left bottom)
				(hide yes)
			)
		)
		(property "Voltage" ""
			(at 312.42 43.18 0)
			(effects
				(font
					(size 1.27 1.27)
				)
				(justify left bottom)
				(hide yes)
			)
		)
		(property "Dielectric" ""
			(at 309.88 43.18 0)
			(effects
				(font
					(size 1.27 1.27)
				)
				(justify left bottom)
				(hide yes)
			)
		)
		(property "DNP" ""
			(at 340.36 63.5 0)
			(effects
				(font
					(size 1.27 1.27)
				)
			)
		)
		(pin "1"
		)
		(pin "2"
		)
		(instances
			(project "artix-dc-scm"
				(path ""
					(reference "C244")
					(unit 1)
				)
			)
		)
	)
	(symbol
		(lib_id "antmicropower:GND")
		(at 250.19 50.8 0)
		(unit 1)
		(exclude_from_sim no)
		(in_bom yes)
		(on_board yes)
		(dnp no)
		(property "Reference" "#PWR0315"
			(at 250.19 57.15 0)
			(effects
				(font
					(size 1.27 1.27)
				)
				(hide yes)
			)
		)
		(property "Value" "GND"
			(at 250.19 54.61 0)
			(effects
				(font
					(size 1.27 1.27)
				)
			)
		)
		(property "Footprint" ""
			(at 250.19 50.8 0)
			(effects
				(font
					(size 1.27 1.27)
				)
				(hide yes)
			)
		)
		(property "Datasheet" ""
			(at 250.19 50.8 0)
			(effects
				(font
					(size 1.27 1.27)
				)
				(hide yes)
			)
		)
		(property "Description" ""
			(at 250.19 50.8 0)
			(effects
				(font
					(size 1.27 1.27)
				)
				(hide yes)
			)
		)
		(property "Author" "Antmicro"
			(at 259.08 58.42 0)
			(effects
				(font
					(size 1.27 1.27)
					(thickness 0.15)
				)
				(justify left bottom)
				(hide yes)
			)
		)
		(property "License" "Apache-2.0"
			(at 259.08 60.96 0)
			(effects
				(font
					(size 1.27 1.27)
					(thickness 0.15)
				)
				(justify left bottom)
				(hide yes)
			)
		)
		(pin "1"
		)
		(instances
			(project "artix-dc-scm"
				(path ""
					(reference "#PWR0315")
					(unit 1)
				)
			)
		)
	)
	(symbol
		(lib_id "antmicropower:GND")
		(at 373.38 50.8 0)
		(mirror y)
		(unit 1)
		(exclude_from_sim no)
		(in_bom yes)
		(on_board yes)
		(dnp no)
		(property "Reference" "#PWR031"
			(at 373.38 57.15 0)
			(effects
				(font
					(size 1.27 1.27)
				)
				(hide yes)
			)
		)
		(property "Value" "GND"
			(at 373.38 54.61 0)
			(effects
				(font
					(size 1.27 1.27)
				)
			)
		)
		(property "Footprint" ""
			(at 373.38 50.8 0)
			(effects
				(font
					(size 1.27 1.27)
				)
				(hide yes)
			)
		)
		(property "Datasheet" ""
			(at 373.38 50.8 0)
			(effects
				(font
					(size 1.27 1.27)
				)
				(hide yes)
			)
		)
		(property "Description" ""
			(at 373.38 50.8 0)
			(effects
				(font
					(size 1.27 1.27)
				)
				(hide yes)
			)
		)
		(property "Author" "Antmicro"
			(at 364.49 58.42 0)
			(effects
				(font
					(size 1.27 1.27)
					(thickness 0.15)
				)
				(justify left bottom)
				(hide yes)
			)
		)
		(property "License" "Apache-2.0"
			(at 364.49 60.96 0)
			(effects
				(font
					(size 1.27 1.27)
					(thickness 0.15)
				)
				(justify left bottom)
				(hide yes)
			)
		)
		(pin "1"
		)
		(instances
			(project "artix-dc-scm"
				(path ""
					(reference "#PWR031")
					(unit 1)
				)
			)
		)
	)
	(symbol
		(lib_id "antmicroLEDIndicationDiscrete:LED_G_0603_LG_L29K-G2J1-24-Z")
		(at 59.69 260.35 0)
		(unit 1)
		(exclude_from_sim no)
		(in_bom yes)
		(on_board yes)
		(dnp no)
		(fields_autoplaced yes)
		(property "Reference" "D11"
			(at 62.23 250.19 0)
			(effects
				(font
					(size 1.27 1.27)
				)
			)
		)
		(property "Value" "LED_G_0603_LG_L29K-G2J1-24-Z"
			(at 82.55 267.97 0)
			(effects
				(font
					(size 1.27 1.27)
					(thickness 0.15)
				)
				(justify left bottom)
				(hide yes)
			)
		)
		(property "Footprint" "antmicro-footprints:LED_0603_1608Metric_G"
			(at 82.55 270.51 0)
			(effects
				(font
					(size 1.27 1.27)
					(thickness 0.15)
				)
				(justify left bottom)
				(hide yes)
			)
		)
		(property "Datasheet" "https://look.ams-osram.com/m/19ee86b3ae0ee95b/original/LG-L29K.pdf"
			(at 82.55 273.05 0)
			(effects
				(font
					(size 1.27 1.27)
					(thickness 0.15)
				)
				(justify left bottom)
				(hide yes)
			)
		)
		(property "Description" "LED, Green, SMD, 0603, 20 mA, 1.7 V, 570 nm"
			(at 59.69 260.35 0)
			(effects
				(font
					(size 1.27 1.27)
				)
				(hide yes)
			)
		)
		(property "MPN" "LG L29K-G2J1-24-Z"
			(at 62.23 252.73 0)
			(effects
				(font
					(size 1.27 1.27)
					(thickness 0.15)
				)
			)
		)
		(property "Manufacturer" "OSRAM"
			(at 82.55 278.13 0)
			(effects
				(font
					(size 1.27 1.27)
					(thickness 0.15)
				)
				(justify left bottom)
				(hide yes)
			)
		)
		(property "Author" "Antmicro"
			(at 82.55 280.67 0)
			(effects
				(font
					(size 1.27 1.27)
					(thickness 0.15)
				)
				(justify left bottom)
				(hide yes)
			)
		)
		(property "License" "Apache-2.0"
			(at 82.55 283.21 0)
			(effects
				(font
					(size 1.27 1.27)
					(thickness 0.15)
				)
				(justify left bottom)
				(hide yes)
			)
		)
		(property "Color" "Green"
			(at 62.23 255.27 0)
			(effects
				(font
					(size 1.27 1.27)
				)
			)
		)
		(pin "1"
		)
		(pin "2"
		)
		(instances
			(project "artix-dc-scm"
				(path ""
					(reference "D11")
					(unit 1)
				)
			)
		)
	)
	(symbol
		(lib_id "antmicroCapacitorsmisc:C_47u_1210")
		(at 67.31 77.47 90)
		(unit 1)
		(exclude_from_sim no)
		(in_bom yes)
		(on_board yes)
		(dnp no)
		(property "Reference" "C178"
			(at 67.945 73.025 90)
			(effects
				(font
					(size 1.27 1.27)
				)
				(justify right)
			)
		)
		(property "Value" "C_47u_1210"
			(at 77.47 57.15 0)
			(effects
				(font
					(size 1.27 1.27)
					(thickness 0.15)
				)
				(justify left bottom)
				(hide yes)
			)
		)
		(property "Footprint" "antmicro-footprints:C_1210_3225Metric"
			(at 80.01 57.15 0)
			(effects
				(font
					(size 1.27 1.27)
					(thickness 0.15)
				)
				(justify left bottom)
				(hide yes)
			)
		)
		(property "Datasheet" "https://www.kemet.com/en/us/capacitors/product/C1210C476K8RACTU.html"
			(at 82.55 57.15 0)
			(effects
				(font
					(size 1.27 1.27)
					(thickness 0.15)
				)
				(justify left bottom)
				(hide yes)
			)
		)
		(property "Description" "SMD Multilayer Ceramic Capacitor, 47 µF, 10 V, 1210 [3225 Metric], ± 10%, X7R, C Series KEMET"
			(at 67.31 77.47 0)
			(effects
				(font
					(size 1.27 1.27)
				)
				(hide yes)
			)
		)
		(property "Manufacturer" "KEMET"
			(at 87.63 57.15 0)
			(effects
				(font
					(size 1.27 1.27)
					(thickness 0.15)
				)
				(justify left bottom)
				(hide yes)
			)
		)
		(property "MPN" "C1210C476K8RACTU"
			(at 85.09 57.15 0)
			(effects
				(font
					(size 1.27 1.27)
					(thickness 0.15)
				)
				(justify left bottom)
				(hide yes)
			)
		)
		(property "Val" "47u"
			(at 67.945 76.835 90)
			(effects
				(font
					(size 1.27 1.27)
					(thickness 0.15)
				)
				(justify right)
			)
		)
		(property "License" "Apache-2.0"
			(at 90.17 57.15 0)
			(effects
				(font
					(size 1.27 1.27)
					(thickness 0.15)
				)
				(justify left bottom)
				(hide yes)
			)
		)
		(property "Author" "Antmicro"
			(at 92.71 57.15 0)
			(effects
				(font
					(size 1.27 1.27)
					(thickness 0.15)
				)
				(justify left bottom)
				(hide yes)
			)
		)
		(property "Voltage" ""
			(at 95.25 57.15 0)
			(effects
				(font
					(size 1.27 1.27)
				)
				(justify left bottom)
				(hide yes)
			)
		)
		(property "Dielectric" ""
			(at 97.79 57.15 0)
			(effects
				(font
					(size 1.27 1.27)
				)
				(justify left bottom)
				(hide yes)
			)
		)
		(property "Public" "False"
			(at 100.33 57.15 0)
			(effects
				(font
					(size 1.27 1.27)
				)
				(justify left bottom)
				(hide yes)
			)
		)
		(pin "1"
		)
		(pin "2"
		)
		(instances
			(project "artix-dc-scm"
				(path ""
					(reference "C178")
					(unit 1)
				)
			)
		)
	)
	(symbol
		(lib_id "antmicropower:GND")
		(at 356.87 50.8 0)
		(mirror y)
		(unit 1)
		(exclude_from_sim no)
		(in_bom yes)
		(on_board yes)
		(dnp no)
		(property "Reference" "#PWR037"
			(at 356.87 57.15 0)
			(effects
				(font
					(size 1.27 1.27)
				)
				(hide yes)
			)
		)
		(property "Value" "GND"
			(at 356.87 54.61 0)
			(effects
				(font
					(size 1.27 1.27)
				)
			)
		)
		(property "Footprint" ""
			(at 356.87 50.8 0)
			(effects
				(font
					(size 1.27 1.27)
				)
				(hide yes)
			)
		)
		(property "Datasheet" ""
			(at 356.87 50.8 0)
			(effects
				(font
					(size 1.27 1.27)
				)
				(hide yes)
			)
		)
		(property "Description" ""
			(at 356.87 50.8 0)
			(effects
				(font
					(size 1.27 1.27)
				)
				(hide yes)
			)
		)
		(property "Author" "Antmicro"
			(at 347.98 58.42 0)
			(effects
				(font
					(size 1.27 1.27)
					(thickness 0.15)
				)
				(justify left bottom)
				(hide yes)
			)
		)
		(property "License" "Apache-2.0"
			(at 347.98 60.96 0)
			(effects
				(font
					(size 1.27 1.27)
					(thickness 0.15)
				)
				(justify left bottom)
				(hide yes)
			)
		)
		(pin "1"
		)
		(instances
			(project "artix-dc-scm"
				(path ""
					(reference "#PWR037")
					(unit 1)
				)
			)
		)
	)
	(symbol
		(lib_id "antmicropower:GND")
		(at 365.76 50.8 0)
		(mirror y)
		(unit 1)
		(exclude_from_sim no)
		(in_bom yes)
		(on_board yes)
		(dnp no)
		(property "Reference" "#PWR033"
			(at 365.76 57.15 0)
			(effects
				(font
					(size 1.27 1.27)
				)
				(hide yes)
			)
		)
		(property "Value" "GND"
			(at 365.76 54.61 0)
			(effects
				(font
					(size 1.27 1.27)
				)
			)
		)
		(property "Footprint" ""
			(at 365.76 50.8 0)
			(effects
				(font
					(size 1.27 1.27)
				)
				(hide yes)
			)
		)
		(property "Datasheet" ""
			(at 365.76 50.8 0)
			(effects
				(font
					(size 1.27 1.27)
				)
				(hide yes)
			)
		)
		(property "Description" ""
			(at 365.76 50.8 0)
			(effects
				(font
					(size 1.27 1.27)
				)
				(hide yes)
			)
		)
		(property "Author" "Antmicro"
			(at 356.87 58.42 0)
			(effects
				(font
					(size 1.27 1.27)
					(thickness 0.15)
				)
				(justify left bottom)
				(hide yes)
			)
		)
		(property "License" "Apache-2.0"
			(at 356.87 60.96 0)
			(effects
				(font
					(size 1.27 1.27)
					(thickness 0.15)
				)
				(justify left bottom)
				(hide yes)
			)
		)
		(pin "1"
		)
		(instances
			(project "artix-dc-scm"
				(path ""
					(reference "#PWR033")
					(unit 1)
				)
			)
		)
	)
	(symbol
		(lib_id "antmicropower:GND")
		(at 67.31 77.47 0)
		(unit 1)
		(exclude_from_sim no)
		(in_bom yes)
		(on_board yes)
		(dnp no)
		(property "Reference" "#PWR083"
			(at 67.31 83.82 0)
			(effects
				(font
					(size 1.27 1.27)
				)
				(hide yes)
			)
		)
		(property "Value" "GND"
			(at 67.31 81.28 0)
			(effects
				(font
					(size 1.27 1.27)
				)
			)
		)
		(property "Footprint" ""
			(at 67.31 77.47 0)
			(effects
				(font
					(size 1.27 1.27)
				)
				(hide yes)
			)
		)
		(property "Datasheet" ""
			(at 67.31 77.47 0)
			(effects
				(font
					(size 1.27 1.27)
				)
				(hide yes)
			)
		)
		(property "Description" ""
			(at 67.31 77.47 0)
			(effects
				(font
					(size 1.27 1.27)
				)
				(hide yes)
			)
		)
		(property "Author" "Antmicro"
			(at 76.2 85.09 0)
			(effects
				(font
					(size 1.27 1.27)
					(thickness 0.15)
				)
				(justify left bottom)
				(hide yes)
			)
		)
		(property "License" "Apache-2.0"
			(at 76.2 87.63 0)
			(effects
				(font
					(size 1.27 1.27)
					(thickness 0.15)
				)
				(justify left bottom)
				(hide yes)
			)
		)
		(pin "1"
		)
		(instances
			(project "artix-dc-scm"
				(path ""
					(reference "#PWR083")
					(unit 1)
				)
			)
		)
	)
	(symbol
		(lib_id "antmicroTransistorsFETsMOSFETsSingle:2N7002_SOT-23-3")
		(at 138.43 270.51 0)
		(unit 1)
		(exclude_from_sim no)
		(in_bom yes)
		(on_board yes)
		(dnp no)
		(fields_autoplaced yes)
		(property "Reference" "Q16"
			(at 149.86 266.6999 0)
			(effects
				(font
					(size 1.27 1.27)
				)
				(justify left)
			)
		)
		(property "Value" "2N7002_SOT-23-3"
			(at 149.86 269.2399 0)
			(effects
				(font
					(size 1.27 1.27)
					(thickness 0.15)
				)
				(justify left)
				(hide yes)
			)
		)
		(property "Footprint" "antmicro-footprints:SOT-23-3"
			(at 161.29 280.67 0)
			(effects
				(font
					(size 1.27 1.27)
					(thickness 0.15)
				)
				(justify left bottom)
				(hide yes)
			)
		)
		(property "Datasheet" "https://www.onsemi.com/pub/Collateral/NDS7002A-D.PDF"
			(at 161.29 283.21 0)
			(effects
				(font
					(size 1.27 1.27)
					(thickness 0.15)
				)
				(justify left bottom)
				(hide yes)
			)
		)
		(property "Description" "Power MOSFET, N Channel, 60 V, 115 mA, 1.2 ohm, SOT-23, Surface Mount"
			(at 138.43 270.51 0)
			(effects
				(font
					(size 1.27 1.27)
				)
				(hide yes)
			)
		)
		(property "MPN" "2N7002"
			(at 149.86 269.2399 0)
			(effects
				(font
					(size 1.27 1.27)
					(thickness 0.15)
				)
				(justify left)
			)
		)
		(property "Manufacturer" "ON Semiconductor"
			(at 161.29 288.29 0)
			(effects
				(font
					(size 1.27 1.27)
					(thickness 0.15)
				)
				(justify left bottom)
				(hide yes)
			)
		)
		(property "Author" "Antmicro"
			(at 161.29 290.83 0)
			(effects
				(font
					(size 1.27 1.27)
					(thickness 0.15)
				)
				(justify left bottom)
				(hide yes)
			)
		)
		(property "License" "Apache-2.0"
			(at 161.29 293.37 0)
			(effects
				(font
					(size 1.27 1.27)
					(thickness 0.15)
				)
				(justify left bottom)
				(hide yes)
			)
		)
		(pin "1"
		)
		(pin "2"
		)
		(pin "3"
		)
		(instances
			(project "artix-dc-scm"
				(path ""
					(reference "Q16")
					(unit 1)
				)
			)
		)
	)
	(symbol
		(lib_id "antmicroCapacitors0402:C_470n_0402")
		(at 232.41 64.77 90)
		(unit 1)
		(exclude_from_sim no)
		(in_bom yes)
		(on_board yes)
		(dnp no)
		(property "Reference" "C121"
			(at 233.045 60.325 90)
			(effects
				(font
					(size 1.27 1.27)
				)
				(justify right)
			)
		)
		(property "Value" "C_470n_0402"
			(at 242.57 44.45 0)
			(effects
				(font
					(size 1.27 1.27)
					(thickness 0.15)
				)
				(justify left bottom)
				(hide yes)
			)
		)
		(property "Footprint" "antmicro-footprints:C_0402_1005Metric"
			(at 245.11 44.45 0)
			(effects
				(font
					(size 1.27 1.27)
					(thickness 0.15)
				)
				(justify left bottom)
				(hide yes)
			)
		)
		(property "Datasheet" "https://product.tdk.com/en/search/capacitor/ceramic/mlcc/info?part_no=C1005X5R1E474M050BB"
			(at 247.65 44.45 0)
			(effects
				(font
					(size 1.27 1.27)
					(thickness 0.15)
				)
				(justify left bottom)
				(hide yes)
			)
		)
		(property "Description" "SMD Multilayer Ceramic Capacitor, 0.47 µF, 25 V, 0402 [1005 Metric], ± 20%, X5R, C"
			(at 232.41 64.77 0)
			(effects
				(font
					(size 1.27 1.27)
				)
				(hide yes)
			)
		)
		(property "Manufacturer" "TDK"
			(at 252.73 44.45 0)
			(effects
				(font
					(size 1.27 1.27)
					(thickness 0.15)
				)
				(justify left bottom)
				(hide yes)
			)
		)
		(property "MPN" "C1005X5R1E474M050BB"
			(at 250.19 44.45 0)
			(effects
				(font
					(size 1.27 1.27)
					(thickness 0.15)
				)
				(justify left bottom)
				(hide yes)
			)
		)
		(property "Val" "470n"
			(at 233.045 64.135 90)
			(effects
				(font
					(size 1.27 1.27)
					(thickness 0.15)
				)
				(justify right)
			)
		)
		(property "License" "Apache-2.0"
			(at 255.27 44.45 0)
			(effects
				(font
					(size 1.27 1.27)
					(thickness 0.15)
				)
				(justify left bottom)
				(hide yes)
			)
		)
		(property "Author" "Antmicro"
			(at 257.81 44.45 0)
			(effects
				(font
					(size 1.27 1.27)
					(thickness 0.15)
				)
				(justify left bottom)
				(hide yes)
			)
		)
		(property "Voltage" ""
			(at 260.35 44.45 0)
			(effects
				(font
					(size 1.27 1.27)
				)
				(justify left bottom)
				(hide yes)
			)
		)
		(property "Dielectric" ""
			(at 262.89 44.45 0)
			(effects
				(font
					(size 1.27 1.27)
				)
				(justify left bottom)
				(hide yes)
			)
		)
		(pin "1"
		)
		(pin "2"
		)
		(instances
			(project "artix-dc-scm"
				(path ""
					(reference "C121")
					(unit 1)
				)
			)
		)
	)
	(symbol
		(lib_id "antmicroResistors0402:R_0R_0402")
		(at 140.97 138.43 270)
		(unit 1)
		(exclude_from_sim no)
		(in_bom yes)
		(on_board yes)
		(dnp no)
		(property "Reference" "R81"
			(at 142.24 139.7 90)
			(effects
				(font
					(size 1.27 1.27)
				)
				(justify left)
			)
		)
		(property "Value" "R_0R_0402"
			(at 128.27 158.75 0)
			(effects
				(font
					(size 1.27 1.27)
					(thickness 0.15)
				)
				(justify left bottom)
				(hide yes)
			)
		)
		(property "Footprint" "antmicro-footprints:R_0402_1005Metric"
			(at 125.73 158.75 0)
			(effects
				(font
					(size 1.27 1.27)
					(thickness 0.15)
				)
				(justify left bottom)
				(hide yes)
			)
		)
		(property "Datasheet" "https://industrial.panasonic.com/cdbs/www-data/pdf/RDA0000/AOA0000C301.pdf"
			(at 123.19 158.75 0)
			(effects
				(font
					(size 1.27 1.27)
					(thickness 0.15)
				)
				(justify left bottom)
				(hide yes)
			)
		)
		(property "Description" "SMD Chip Resistor, Jumper, 0 ohm, 100 mW, 0402 [1005 Metric], Thick Film, General Purpose"
			(at 140.97 138.43 0)
			(effects
				(font
					(size 1.27 1.27)
				)
				(hide yes)
			)
		)
		(property "Manufacturer" "Panasonic"
			(at 118.11 158.75 0)
			(effects
				(font
					(size 1.27 1.27)
					(thickness 0.15)
				)
				(justify left bottom)
				(hide yes)
			)
		)
		(property "MPN" "ERJ2GE0R00X"
			(at 120.65 158.75 0)
			(effects
				(font
					(size 1.27 1.27)
					(thickness 0.15)
				)
				(justify left bottom)
				(hide yes)
			)
		)
		(property "Val" "0R"
			(at 142.24 142.24 90)
			(effects
				(font
					(size 1.27 1.27)
					(thickness 0.15)
				)
				(justify left)
			)
		)
		(property "License" "Apache-2.0"
			(at 115.57 158.75 0)
			(effects
				(font
					(size 1.27 1.27)
					(thickness 0.15)
				)
				(justify left bottom)
				(hide yes)
			)
		)
		(property "Author" "Antmicro"
			(at 113.03 158.75 0)
			(effects
				(font
					(size 1.27 1.27)
					(thickness 0.15)
				)
				(justify left bottom)
				(hide yes)
			)
		)
		(property "Tolerance" "~"
			(at 130.81 158.75 0)
			(effects
				(font
					(size 1.27 1.27)
				)
				(justify left bottom)
				(hide yes)
			)
		)
		(property "Current" "1A"
			(at 110.49 158.75 0)
			(effects
				(font
					(size 1.27 1.27)
					(thickness 0.15)
				)
				(justify left bottom)
				(hide yes)
			)
		)
		(pin "1"
		)
		(pin "2"
		)
		(instances
			(project "artix-dc-scm"
				(path ""
					(reference "R81")
					(unit 1)
				)
			)
		)
	)
	(symbol
		(lib_id "antmicroTransistorsFETsMOSFETsSingle:2N7002_SOT-23-3")
		(at 138.43 238.76 0)
		(unit 1)
		(exclude_from_sim no)
		(in_bom yes)
		(on_board yes)
		(dnp no)
		(fields_autoplaced yes)
		(property "Reference" "Q15"
			(at 149.86 234.9499 0)
			(effects
				(font
					(size 1.27 1.27)
				)
				(justify left)
			)
		)
		(property "Value" "2N7002_SOT-23-3"
			(at 149.225 237.4899 0)
			(effects
				(font
					(size 1.27 1.27)
					(thickness 0.15)
				)
				(justify left)
				(hide yes)
			)
		)
		(property "Footprint" "antmicro-footprints:SOT-23-3"
			(at 161.29 248.92 0)
			(effects
				(font
					(size 1.27 1.27)
					(thickness 0.15)
				)
				(justify left bottom)
				(hide yes)
			)
		)
		(property "Datasheet" "https://www.onsemi.com/pub/Collateral/NDS7002A-D.PDF"
			(at 161.29 251.46 0)
			(effects
				(font
					(size 1.27 1.27)
					(thickness 0.15)
				)
				(justify left bottom)
				(hide yes)
			)
		)
		(property "Description" "Power MOSFET, N Channel, 60 V, 115 mA, 1.2 ohm, SOT-23, Surface Mount"
			(at 138.43 238.76 0)
			(effects
				(font
					(size 1.27 1.27)
				)
				(hide yes)
			)
		)
		(property "MPN" "2N7002"
			(at 149.86 237.4899 0)
			(effects
				(font
					(size 1.27 1.27)
					(thickness 0.15)
				)
				(justify left)
			)
		)
		(property "Manufacturer" "ON Semiconductor"
			(at 161.29 256.54 0)
			(effects
				(font
					(size 1.27 1.27)
					(thickness 0.15)
				)
				(justify left bottom)
				(hide yes)
			)
		)
		(property "Author" "Antmicro"
			(at 161.29 259.08 0)
			(effects
				(font
					(size 1.27 1.27)
					(thickness 0.15)
				)
				(justify left bottom)
				(hide yes)
			)
		)
		(property "License" "Apache-2.0"
			(at 161.29 261.62 0)
			(effects
				(font
					(size 1.27 1.27)
					(thickness 0.15)
				)
				(justify left bottom)
				(hide yes)
			)
		)
		(pin "1"
		)
		(pin "2"
		)
		(pin "3"
		)
		(instances
			(project "artix-dc-scm"
				(path ""
					(reference "Q15")
					(unit 1)
				)
			)
		)
	)
	(symbol
		(lib_id "antmicroResistors0402:R_1k_0402")
		(at 168.91 228.6 0)
		(unit 1)
		(exclude_from_sim no)
		(in_bom yes)
		(on_board yes)
		(dnp no)
		(property "Reference" "R131"
			(at 171.45 226.06 0)
			(effects
				(font
					(size 1.27 1.27)
				)
			)
		)
		(property "Value" "R_1k_0402"
			(at 189.23 241.3 0)
			(effects
				(font
					(size 1.27 1.27)
					(thickness 0.15)
				)
				(justify left bottom)
				(hide yes)
			)
		)
		(property "Footprint" "antmicro-footprints:R_0402_1005Metric"
			(at 189.23 243.84 0)
			(effects
				(font
					(size 1.27 1.27)
					(thickness 0.15)
				)
				(justify left bottom)
				(hide yes)
			)
		)
		(property "Datasheet" "https://www.bourns.com/docs/product-datasheets/cr.pdf"
			(at 189.23 246.38 0)
			(effects
				(font
					(size 1.27 1.27)
					(thickness 0.15)
				)
				(justify left bottom)
				(hide yes)
			)
		)
		(property "Description" "SMD Chip Resistor, 1 kohm, ± 1%, 63 mW, 0402 [1005 Metric], Thick Film, General Purpose"
			(at 168.91 228.6 0)
			(effects
				(font
					(size 1.27 1.27)
				)
				(hide yes)
			)
		)
		(property "Manufacturer" "Bourns"
			(at 189.23 251.46 0)
			(effects
				(font
					(size 1.27 1.27)
					(thickness 0.15)
				)
				(justify left bottom)
				(hide yes)
			)
		)
		(property "MPN" "CR0402-FX-1001GLF"
			(at 189.23 248.92 0)
			(effects
				(font
					(size 1.27 1.27)
					(thickness 0.15)
				)
				(justify left bottom)
				(hide yes)
			)
		)
		(property "Val" "1k"
			(at 171.45 231.14 0)
			(effects
				(font
					(size 1.27 1.27)
					(thickness 0.15)
				)
			)
		)
		(property "License" "Apache-2.0"
			(at 189.23 254 0)
			(effects
				(font
					(size 1.27 1.27)
					(thickness 0.15)
				)
				(justify left bottom)
				(hide yes)
			)
		)
		(property "Author" "Antmicro"
			(at 189.23 256.54 0)
			(effects
				(font
					(size 1.27 1.27)
					(thickness 0.15)
				)
				(justify left bottom)
				(hide yes)
			)
		)
		(property "Tolerance" "1%"
			(at 189.23 238.76 0)
			(effects
				(font
					(size 1.27 1.27)
				)
				(justify left bottom)
				(hide yes)
			)
		)
		(pin "1"
		)
		(pin "2"
		)
		(instances
			(project "artix-dc-scm"
				(path ""
					(reference "R131")
					(unit 1)
				)
			)
		)
	)
	(symbol
		(lib_id "antmicropower:GND")
		(at 250.19 64.77 0)
		(unit 1)
		(exclude_from_sim no)
		(in_bom yes)
		(on_board yes)
		(dnp no)
		(property "Reference" "#PWR0317"
			(at 250.19 71.12 0)
			(effects
				(font
					(size 1.27 1.27)
				)
				(hide yes)
			)
		)
		(property "Value" "GND"
			(at 250.19 68.58 0)
			(effects
				(font
					(size 1.27 1.27)
				)
			)
		)
		(property "Footprint" ""
			(at 250.19 64.77 0)
			(effects
				(font
					(size 1.27 1.27)
				)
				(hide yes)
			)
		)
		(property "Datasheet" ""
			(at 250.19 64.77 0)
			(effects
				(font
					(size 1.27 1.27)
				)
				(hide yes)
			)
		)
		(property "Description" ""
			(at 250.19 64.77 0)
			(effects
				(font
					(size 1.27 1.27)
				)
				(hide yes)
			)
		)
		(property "Author" "Antmicro"
			(at 259.08 72.39 0)
			(effects
				(font
					(size 1.27 1.27)
					(thickness 0.15)
				)
				(justify left bottom)
				(hide yes)
			)
		)
		(property "License" "Apache-2.0"
			(at 259.08 74.93 0)
			(effects
				(font
					(size 1.27 1.27)
					(thickness 0.15)
				)
				(justify left bottom)
				(hide yes)
			)
		)
		(pin "1"
		)
		(instances
			(project "artix-dc-scm"
				(path ""
					(reference "#PWR0317")
					(unit 1)
				)
			)
		)
	)
	(symbol
		(lib_id "antmicropower:GND")
		(at 146.05 274.32 0)
		(unit 1)
		(exclude_from_sim no)
		(in_bom yes)
		(on_board yes)
		(dnp no)
		(property "Reference" "#PWR0327"
			(at 146.05 280.67 0)
			(effects
				(font
					(size 1.27 1.27)
				)
				(hide yes)
			)
		)
		(property "Value" "GND"
			(at 146.05 278.13 0)
			(effects
				(font
					(size 1.27 1.27)
				)
			)
		)
		(property "Footprint" ""
			(at 146.05 274.32 0)
			(effects
				(font
					(size 1.27 1.27)
				)
				(hide yes)
			)
		)
		(property "Datasheet" ""
			(at 146.05 274.32 0)
			(effects
				(font
					(size 1.27 1.27)
				)
				(hide yes)
			)
		)
		(property "Description" ""
			(at 146.05 274.32 0)
			(effects
				(font
					(size 1.27 1.27)
				)
				(hide yes)
			)
		)
		(property "Author" "Antmicro"
			(at 154.94 281.94 0)
			(effects
				(font
					(size 1.27 1.27)
					(thickness 0.15)
				)
				(justify left bottom)
				(hide yes)
			)
		)
		(property "License" "Apache-2.0"
			(at 154.94 284.48 0)
			(effects
				(font
					(size 1.27 1.27)
					(thickness 0.15)
				)
				(justify left bottom)
				(hide yes)
			)
		)
		(pin "1"
		)
		(instances
			(project "artix-dc-scm"
				(path ""
					(reference "#PWR0327")
					(unit 1)
				)
			)
		)
	)
	(symbol
		(lib_id "antmicroCapacitors0402:C_470n_0402")
		(at 349.25 50.8 270)
		(mirror x)
		(unit 1)
		(exclude_from_sim no)
		(in_bom yes)
		(on_board yes)
		(dnp no)
		(property "Reference" "C114"
			(at 348.615 46.355 90)
			(effects
				(font
					(size 1.27 1.27)
				)
				(justify right)
			)
		)
		(property "Value" "C_470n_0402"
			(at 339.09 30.48 0)
			(effects
				(font
					(size 1.27 1.27)
					(thickness 0.15)
				)
				(justify left bottom)
				(hide yes)
			)
		)
		(property "Footprint" "antmicro-footprints:C_0402_1005Metric"
			(at 336.55 30.48 0)
			(effects
				(font
					(size 1.27 1.27)
					(thickness 0.15)
				)
				(justify left bottom)
				(hide yes)
			)
		)
		(property "Datasheet" "https://product.tdk.com/en/search/capacitor/ceramic/mlcc/info?part_no=C1005X5R1E474M050BB"
			(at 334.01 30.48 0)
			(effects
				(font
					(size 1.27 1.27)
					(thickness 0.15)
				)
				(justify left bottom)
				(hide yes)
			)
		)
		(property "Description" "SMD Multilayer Ceramic Capacitor, 0.47 µF, 25 V, 0402 [1005 Metric], ± 20%, X5R, C"
			(at 349.25 50.8 0)
			(effects
				(font
					(size 1.27 1.27)
				)
				(hide yes)
			)
		)
		(property "Manufacturer" "TDK"
			(at 328.93 30.48 0)
			(effects
				(font
					(size 1.27 1.27)
					(thickness 0.15)
				)
				(justify left bottom)
				(hide yes)
			)
		)
		(property "MPN" "C1005X5R1E474M050BB"
			(at 331.47 30.48 0)
			(effects
				(font
					(size 1.27 1.27)
					(thickness 0.15)
				)
				(justify left bottom)
				(hide yes)
			)
		)
		(property "Val" "470n"
			(at 348.615 50.165 90)
			(effects
				(font
					(size 1.27 1.27)
					(thickness 0.15)
				)
				(justify right)
			)
		)
		(property "License" "Apache-2.0"
			(at 326.39 30.48 0)
			(effects
				(font
					(size 1.27 1.27)
					(thickness 0.15)
				)
				(justify left bottom)
				(hide yes)
			)
		)
		(property "Author" "Antmicro"
			(at 323.85 30.48 0)
			(effects
				(font
					(size 1.27 1.27)
					(thickness 0.15)
				)
				(justify left bottom)
				(hide yes)
			)
		)
		(property "Voltage" ""
			(at 321.31 30.48 0)
			(effects
				(font
					(size 1.27 1.27)
				)
				(justify left bottom)
				(hide yes)
			)
		)
		(property "Dielectric" ""
			(at 318.77 30.48 0)
			(effects
				(font
					(size 1.27 1.27)
				)
				(justify left bottom)
				(hide yes)
			)
		)
		(property "DNP" ""
			(at 349.25 50.8 0)
			(effects
				(font
					(size 1.27 1.27)
				)
			)
		)
		(pin "1"
		)
		(pin "2"
		)
		(instances
			(project "artix-dc-scm"
				(path ""
					(reference "C114")
					(unit 1)
				)
			)
		)
	)
	(symbol
		(lib_id "antmicroCapacitors0603:C_4u7_0603")
		(at 356.87 50.8 270)
		(mirror x)
		(unit 1)
		(exclude_from_sim no)
		(in_bom yes)
		(on_board yes)
		(dnp no)
		(property "Reference" "C108"
			(at 356.235 46.355 90)
			(effects
				(font
					(size 1.27 1.27)
				)
				(justify right)
			)
		)
		(property "Value" "C_4u7_0603"
			(at 346.71 30.48 0)
			(effects
				(font
					(size 1.27 1.27)
					(thickness 0.15)
				)
				(justify left bottom)
				(hide yes)
			)
		)
		(property "Footprint" "antmicro-footprints:C_0603_1608Metric"
			(at 344.17 30.48 0)
			(effects
				(font
					(size 1.27 1.27)
					(thickness 0.15)
				)
				(justify left bottom)
				(hide yes)
			)
		)
		(property "Datasheet" "https://product.tdk.com/en/search/capacitor/ceramic/mlcc/info?part_no=C1608X5R1V475M080AC"
			(at 341.63 30.48 0)
			(effects
				(font
					(size 1.27 1.27)
					(thickness 0.15)
				)
				(justify left bottom)
				(hide yes)
			)
		)
		(property "Description" "SMD Multilayer Ceramic Capacitor, 4.7 µF, 35 V, 0603 [1608 Metric], ± 20%, X5R, C"
			(at 356.87 50.8 0)
			(effects
				(font
					(size 1.27 1.27)
				)
				(hide yes)
			)
		)
		(property "Manufacturer" "TDK"
			(at 336.55 30.48 0)
			(effects
				(font
					(size 1.27 1.27)
					(thickness 0.15)
				)
				(justify left bottom)
				(hide yes)
			)
		)
		(property "MPN" "C1608X5R1V475M080AC"
			(at 339.09 30.48 0)
			(effects
				(font
					(size 1.27 1.27)
					(thickness 0.15)
				)
				(justify left bottom)
				(hide yes)
			)
		)
		(property "Val" "4u7"
			(at 356.235 50.165 90)
			(effects
				(font
					(size 1.27 1.27)
					(thickness 0.15)
				)
				(justify right)
			)
		)
		(property "License" "Apache-2.0"
			(at 334.01 30.48 0)
			(effects
				(font
					(size 1.27 1.27)
					(thickness 0.15)
				)
				(justify left bottom)
				(hide yes)
			)
		)
		(property "Author" "Antmicro"
			(at 331.47 30.48 0)
			(effects
				(font
					(size 1.27 1.27)
					(thickness 0.15)
				)
				(justify left bottom)
				(hide yes)
			)
		)
		(property "Voltage" ""
			(at 328.93 30.48 0)
			(effects
				(font
					(size 1.27 1.27)
				)
				(justify left bottom)
				(hide yes)
			)
		)
		(property "Dielectric" ""
			(at 326.39 30.48 0)
			(effects
				(font
					(size 1.27 1.27)
				)
				(justify left bottom)
				(hide yes)
			)
		)
		(property "DNP" ""
			(at 356.87 50.8 0)
			(effects
				(font
					(size 1.27 1.27)
				)
			)
		)
		(pin "1"
		)
		(pin "2"
		)
		(instances
			(project "artix-dc-scm"
				(path ""
					(reference "C108")
					(unit 1)
				)
			)
		)
	)
	(symbol
		(lib_id "antmicroResistors0402:R_1k_0402")
		(at 73.66 196.85 0)
		(unit 1)
		(exclude_from_sim no)
		(in_bom yes)
		(on_board yes)
		(dnp no)
		(property "Reference" "R128"
			(at 76.2 194.31 0)
			(effects
				(font
					(size 1.27 1.27)
				)
			)
		)
		(property "Value" "R_1k_0402"
			(at 93.98 209.55 0)
			(effects
				(font
					(size 1.27 1.27)
					(thickness 0.15)
				)
				(justify left bottom)
				(hide yes)
			)
		)
		(property "Footprint" "antmicro-footprints:R_0402_1005Metric"
			(at 93.98 212.09 0)
			(effects
				(font
					(size 1.27 1.27)
					(thickness 0.15)
				)
				(justify left bottom)
				(hide yes)
			)
		)
		(property "Datasheet" "https://www.bourns.com/docs/product-datasheets/cr.pdf"
			(at 93.98 214.63 0)
			(effects
				(font
					(size 1.27 1.27)
					(thickness 0.15)
				)
				(justify left bottom)
				(hide yes)
			)
		)
		(property "Description" "SMD Chip Resistor, 1 kohm, ± 1%, 63 mW, 0402 [1005 Metric], Thick Film, General Purpose"
			(at 73.66 196.85 0)
			(effects
				(font
					(size 1.27 1.27)
				)
				(hide yes)
			)
		)
		(property "Manufacturer" "Bourns"
			(at 93.98 219.71 0)
			(effects
				(font
					(size 1.27 1.27)
					(thickness 0.15)
				)
				(justify left bottom)
				(hide yes)
			)
		)
		(property "MPN" "CR0402-FX-1001GLF"
			(at 93.98 217.17 0)
			(effects
				(font
					(size 1.27 1.27)
					(thickness 0.15)
				)
				(justify left bottom)
				(hide yes)
			)
		)
		(property "Val" "1k"
			(at 76.2 199.39 0)
			(effects
				(font
					(size 1.27 1.27)
					(thickness 0.15)
				)
			)
		)
		(property "License" "Apache-2.0"
			(at 93.98 222.25 0)
			(effects
				(font
					(size 1.27 1.27)
					(thickness 0.15)
				)
				(justify left bottom)
				(hide yes)
			)
		)
		(property "Author" "Antmicro"
			(at 93.98 224.79 0)
			(effects
				(font
					(size 1.27 1.27)
					(thickness 0.15)
				)
				(justify left bottom)
				(hide yes)
			)
		)
		(property "Tolerance" "1%"
			(at 93.98 207.01 0)
			(effects
				(font
					(size 1.27 1.27)
				)
				(justify left bottom)
				(hide yes)
			)
		)
		(pin "1"
		)
		(pin "2"
		)
		(instances
			(project "artix-dc-scm"
				(path ""
					(reference "R128")
					(unit 1)
				)
			)
		)
	)
	(symbol
		(lib_id "antmicroResistors0402:R_200R_0402")
		(at 100.33 72.39 270)
		(unit 1)
		(exclude_from_sim no)
		(in_bom yes)
		(on_board yes)
		(dnp no)
		(property "Reference" "R88"
			(at 101.6 73.66 90)
			(effects
				(font
					(size 1.27 1.27)
				)
				(justify left)
			)
		)
		(property "Value" "R_200R_0402"
			(at 87.63 92.71 0)
			(effects
				(font
					(size 1.27 1.27)
					(thickness 0.15)
				)
				(justify left bottom)
				(hide yes)
			)
		)
		(property "Footprint" "antmicro-footprints:R_0402_1005Metric"
			(at 85.09 92.71 0)
			(effects
				(font
					(size 1.27 1.27)
					(thickness 0.15)
				)
				(justify left bottom)
				(hide yes)
			)
		)
		(property "Datasheet" "https://www.bourns.com/docs/product-datasheets/cr.pdf"
			(at 82.55 92.71 0)
			(effects
				(font
					(size 1.27 1.27)
					(thickness 0.15)
				)
				(justify left bottom)
				(hide yes)
			)
		)
		(property "Description" "SMD Chip Resistor, 200 ohm, ± 1%, 62.5 mW, 0402 [1005 Metric], Thick Film, General Purpose"
			(at 100.33 72.39 0)
			(effects
				(font
					(size 1.27 1.27)
				)
				(hide yes)
			)
		)
		(property "Manufacturer" "Bourns"
			(at 77.47 92.71 0)
			(effects
				(font
					(size 1.27 1.27)
					(thickness 0.15)
				)
				(justify left bottom)
				(hide yes)
			)
		)
		(property "MPN" "CR0402-FX-2000GLF"
			(at 80.01 92.71 0)
			(effects
				(font
					(size 1.27 1.27)
					(thickness 0.15)
				)
				(justify left bottom)
				(hide yes)
			)
		)
		(property "Val" "200R"
			(at 101.6 76.2 90)
			(effects
				(font
					(size 1.27 1.27)
					(thickness 0.15)
				)
				(justify left)
			)
		)
		(property "License" "Apache-2.0"
			(at 74.93 92.71 0)
			(effects
				(font
					(size 1.27 1.27)
					(thickness 0.15)
				)
				(justify left bottom)
				(hide yes)
			)
		)
		(property "Author" "Antmicro"
			(at 72.39 92.71 0)
			(effects
				(font
					(size 1.27 1.27)
					(thickness 0.15)
				)
				(justify left bottom)
				(hide yes)
			)
		)
		(property "Tolerance" "1%"
			(at 90.17 92.71 0)
			(effects
				(font
					(size 1.27 1.27)
				)
				(justify left bottom)
				(hide yes)
			)
		)
		(pin "1"
		)
		(pin "2"
		)
		(instances
			(project "artix-dc-scm"
				(path ""
					(reference "R88")
					(unit 1)
				)
			)
		)
	)
	(symbol
		(lib_id "antmicroTestPoints:TP_1mm_SMD")
		(at 93.98 88.9 270)
		(unit 1)
		(exclude_from_sim no)
		(in_bom no)
		(on_board yes)
		(dnp no)
		(property "Reference" "TP5"
			(at 92.075 93.98 90)
			(effects
				(font
					(size 1.27 1.27)
				)
				(justify left)
			)
		)
		(property "Value" "TP_1mm_SMD"
			(at 91.44 88.9 0)
			(effects
				(font
					(size 1.27 1.27)
				)
				(hide yes)
			)
		)
		(property "Footprint" "antmicro-footprints:TP_SMD_1mm"
			(at 83.82 104.14 0)
			(effects
				(font
					(size 1.27 1.27)
					(thickness 0.15)
				)
				(justify left bottom)
				(hide yes)
			)
		)
		(property "Datasheet" ""
			(at 81.28 104.14 0)
			(effects
				(font
					(size 1.27 1.27)
					(thickness 0.15)
				)
				(justify left bottom)
				(hide yes)
			)
		)
		(property "Description" "Test point 1mm SMD"
			(at 93.98 88.9 0)
			(effects
				(font
					(size 1.27 1.27)
				)
				(hide yes)
			)
		)
		(property "MPN" ""
			(at 93.98 88.9 0)
			(effects
				(font
					(size 1.27 1.27)
				)
				(hide yes)
			)
		)
		(property "Manufacturer" ""
			(at 93.98 88.9 0)
			(effects
				(font
					(size 1.27 1.27)
				)
				(hide yes)
			)
		)
		(property "Author" "Antmicro"
			(at 78.74 104.14 0)
			(effects
				(font
					(size 1.27 1.27)
					(thickness 0.15)
				)
				(justify left bottom)
				(hide yes)
			)
		)
		(property "License" "Apache-2.0"
			(at 76.2 104.14 0)
			(effects
				(font
					(size 1.27 1.27)
					(thickness 0.15)
				)
				(justify left bottom)
				(hide yes)
			)
		)
		(pin "1"
		)
		(instances
			(project "artix-dc-scm"
				(path ""
					(reference "TP5")
					(unit 1)
				)
			)
		)
	)
	(symbol
		(lib_id "antmicroLEDIndicationDiscrete:LED_G_0603_LG_L29K-G2J1-24-Z")
		(at 59.69 228.6 0)
		(unit 1)
		(exclude_from_sim no)
		(in_bom yes)
		(on_board yes)
		(dnp no)
		(fields_autoplaced yes)
		(property "Reference" "D10"
			(at 62.23 218.44 0)
			(effects
				(font
					(size 1.27 1.27)
				)
			)
		)
		(property "Value" "LED_G_0603_LG_L29K-G2J1-24-Z"
			(at 82.55 236.22 0)
			(effects
				(font
					(size 1.27 1.27)
					(thickness 0.15)
				)
				(justify left bottom)
				(hide yes)
			)
		)
		(property "Footprint" "antmicro-footprints:LED_0603_1608Metric_G"
			(at 82.55 238.76 0)
			(effects
				(font
					(size 1.27 1.27)
					(thickness 0.15)
				)
				(justify left bottom)
				(hide yes)
			)
		)
		(property "Datasheet" "https://look.ams-osram.com/m/19ee86b3ae0ee95b/original/LG-L29K.pdf"
			(at 82.55 241.3 0)
			(effects
				(font
					(size 1.27 1.27)
					(thickness 0.15)
				)
				(justify left bottom)
				(hide yes)
			)
		)
		(property "Description" "LED, Green, SMD, 0603, 20 mA, 1.7 V, 570 nm"
			(at 59.69 228.6 0)
			(effects
				(font
					(size 1.27 1.27)
				)
				(hide yes)
			)
		)
		(property "MPN" "LG L29K-G2J1-24-Z"
			(at 62.23 220.98 0)
			(effects
				(font
					(size 1.27 1.27)
					(thickness 0.15)
				)
			)
		)
		(property "Manufacturer" "OSRAM"
			(at 82.55 246.38 0)
			(effects
				(font
					(size 1.27 1.27)
					(thickness 0.15)
				)
				(justify left bottom)
				(hide yes)
			)
		)
		(property "Author" "Antmicro"
			(at 82.55 248.92 0)
			(effects
				(font
					(size 1.27 1.27)
					(thickness 0.15)
				)
				(justify left bottom)
				(hide yes)
			)
		)
		(property "License" "Apache-2.0"
			(at 82.55 251.46 0)
			(effects
				(font
					(size 1.27 1.27)
					(thickness 0.15)
				)
				(justify left bottom)
				(hide yes)
			)
		)
		(property "Color" "Green"
			(at 62.23 223.52 0)
			(effects
				(font
					(size 1.27 1.27)
				)
			)
		)
		(pin "1"
		)
		(pin "2"
		)
		(instances
			(project "artix-dc-scm"
				(path ""
					(reference "D10")
					(unit 1)
				)
			)
		)
	)
	(symbol
		(lib_id "antmicroResistors0402:R_0R_0402")
		(at 123.19 138.43 270)
		(unit 1)
		(exclude_from_sim no)
		(in_bom no)
		(on_board yes)
		(dnp yes)
		(property "Reference" "R83"
			(at 124.46 139.7 90)
			(effects
				(font
					(size 1.27 1.27)
				)
				(justify left)
			)
		)
		(property "Value" "R_0R_0402"
			(at 110.49 158.75 0)
			(effects
				(font
					(size 1.27 1.27)
					(thickness 0.15)
				)
				(justify left bottom)
				(hide yes)
			)
		)
		(property "Footprint" "antmicro-footprints:R_0402_1005Metric"
			(at 107.95 158.75 0)
			(effects
				(font
					(size 1.27 1.27)
					(thickness 0.15)
				)
				(justify left bottom)
				(hide yes)
			)
		)
		(property "Datasheet" "https://industrial.panasonic.com/cdbs/www-data/pdf/RDA0000/AOA0000C301.pdf"
			(at 105.41 158.75 0)
			(effects
				(font
					(size 1.27 1.27)
					(thickness 0.15)
				)
				(justify left bottom)
				(hide yes)
			)
		)
		(property "Description" "SMD Chip Resistor, Jumper, 0 ohm, 100 mW, 0402 [1005 Metric], Thick Film, General Purpose"
			(at 123.19 138.43 0)
			(effects
				(font
					(size 1.27 1.27)
				)
				(hide yes)
			)
		)
		(property "Manufacturer" "Panasonic"
			(at 100.33 158.75 0)
			(effects
				(font
					(size 1.27 1.27)
					(thickness 0.15)
				)
				(justify left bottom)
				(hide yes)
			)
		)
		(property "MPN" "ERJ2GE0R00X"
			(at 102.87 158.75 0)
			(effects
				(font
					(size 1.27 1.27)
					(thickness 0.15)
				)
				(justify left bottom)
				(hide yes)
			)
		)
		(property "Val" "0R"
			(at 124.46 142.24 90)
			(effects
				(font
					(size 1.27 1.27)
					(thickness 0.15)
				)
				(justify left)
			)
		)
		(property "License" "Apache-2.0"
			(at 97.79 158.75 0)
			(effects
				(font
					(size 1.27 1.27)
					(thickness 0.15)
				)
				(justify left bottom)
				(hide yes)
			)
		)
		(property "Author" "Antmicro"
			(at 95.25 158.75 0)
			(effects
				(font
					(size 1.27 1.27)
					(thickness 0.15)
				)
				(justify left bottom)
				(hide yes)
			)
		)
		(property "Tolerance" "~"
			(at 113.03 158.75 0)
			(effects
				(font
					(size 1.27 1.27)
				)
				(justify left bottom)
				(hide yes)
			)
		)
		(property "Current" "1A"
			(at 92.71 158.75 0)
			(effects
				(font
					(size 1.27 1.27)
					(thickness 0.15)
				)
				(justify left bottom)
				(hide yes)
			)
		)
		(pin "1"
		)
		(pin "2"
		)
		(instances
			(project "artix-dc-scm"
				(path ""
					(reference "R83")
					(unit 1)
				)
			)
		)
	)
	(symbol
		(lib_id "antmicroResistors0402:R_100R_0402")
		(at 109.22 72.39 270)
		(unit 1)
		(exclude_from_sim no)
		(in_bom yes)
		(on_board yes)
		(dnp no)
		(property "Reference" "R86"
			(at 110.49 73.66 90)
			(effects
				(font
					(size 1.27 1.27)
				)
				(justify left)
			)
		)
		(property "Value" "R_100R_0402"
			(at 96.52 92.71 0)
			(effects
				(font
					(size 1.27 1.27)
					(thickness 0.15)
				)
				(justify left bottom)
				(hide yes)
			)
		)
		(property "Footprint" "antmicro-footprints:R_0402_1005Metric"
			(at 93.98 92.71 0)
			(effects
				(font
					(size 1.27 1.27)
					(thickness 0.15)
				)
				(justify left bottom)
				(hide yes)
			)
		)
		(property "Datasheet" "https://www.bourns.com/docs/product-datasheets/cr.pdf"
			(at 91.44 92.71 0)
			(effects
				(font
					(size 1.27 1.27)
					(thickness 0.15)
				)
				(justify left bottom)
				(hide yes)
			)
		)
		(property "Description" "SMD Chip Resistor, 100 ohm, ± 1%, 62.5 mW, 0402 [1005 Metric], Thick Film, General Purpose"
			(at 109.22 72.39 0)
			(effects
				(font
					(size 1.27 1.27)
				)
				(hide yes)
			)
		)
		(property "Manufacturer" "Bourns"
			(at 86.36 92.71 0)
			(effects
				(font
					(size 1.27 1.27)
					(thickness 0.15)
				)
				(justify left bottom)
				(hide yes)
			)
		)
		(property "MPN" "CR0402-FX-1000GLF"
			(at 88.9 92.71 0)
			(effects
				(font
					(size 1.27 1.27)
					(thickness 0.15)
				)
				(justify left bottom)
				(hide yes)
			)
		)
		(property "Val" "100R"
			(at 110.49 76.2 90)
			(effects
				(font
					(size 1.27 1.27)
					(thickness 0.15)
				)
				(justify left)
			)
		)
		(property "License" "Apache-2.0"
			(at 83.82 92.71 0)
			(effects
				(font
					(size 1.27 1.27)
					(thickness 0.15)
				)
				(justify left bottom)
				(hide yes)
			)
		)
		(property "Author" "Antmicro"
			(at 81.28 92.71 0)
			(effects
				(font
					(size 1.27 1.27)
					(thickness 0.15)
				)
				(justify left bottom)
				(hide yes)
			)
		)
		(property "Tolerance" "1%"
			(at 99.06 92.71 0)
			(effects
				(font
					(size 1.27 1.27)
				)
				(justify left bottom)
				(hide yes)
			)
		)
		(property "DNP" ""
			(at 109.22 74.93 0)
			(effects
				(font
					(size 1.27 1.27)
				)
			)
		)
		(pin "1"
		)
		(pin "2"
		)
		(instances
			(project "artix-dc-scm"
				(path ""
					(reference "R86")
					(unit 1)
				)
			)
		)
	)
	(symbol
		(lib_id "antmicropower:GND")
		(at 63.5 133.35 0)
		(unit 1)
		(exclude_from_sim no)
		(in_bom yes)
		(on_board yes)
		(dnp no)
		(property "Reference" "#PWR061"
			(at 63.5 139.7 0)
			(effects
				(font
					(size 1.27 1.27)
				)
				(hide yes)
			)
		)
		(property "Value" "GND"
			(at 63.5 137.16 0)
			(effects
				(font
					(size 1.27 1.27)
				)
			)
		)
		(property "Footprint" ""
			(at 63.5 133.35 0)
			(effects
				(font
					(size 1.27 1.27)
				)
				(hide yes)
			)
		)
		(property "Datasheet" ""
			(at 63.5 133.35 0)
			(effects
				(font
					(size 1.27 1.27)
				)
				(hide yes)
			)
		)
		(property "Description" ""
			(at 63.5 133.35 0)
			(effects
				(font
					(size 1.27 1.27)
				)
				(hide yes)
			)
		)
		(property "Author" "Antmicro"
			(at 72.39 140.97 0)
			(effects
				(font
					(size 1.27 1.27)
					(thickness 0.15)
				)
				(justify left bottom)
				(hide yes)
			)
		)
		(property "License" "Apache-2.0"
			(at 72.39 143.51 0)
			(effects
				(font
					(size 1.27 1.27)
					(thickness 0.15)
				)
				(justify left bottom)
				(hide yes)
			)
		)
		(pin "1"
		)
		(instances
			(project "artix-dc-scm"
				(path ""
					(reference "#PWR061")
					(unit 1)
				)
			)
		)
	)
	(symbol
		(lib_id "antmicroResistors0402:R_0R_0402")
		(at 140.97 151.13 90)
		(unit 1)
		(exclude_from_sim no)
		(in_bom no)
		(on_board yes)
		(dnp yes)
		(property "Reference" "R82"
			(at 142.24 147.32 90)
			(effects
				(font
					(size 1.27 1.27)
				)
				(justify right)
			)
		)
		(property "Value" "R_0R_0402"
			(at 153.67 130.81 0)
			(effects
				(font
					(size 1.27 1.27)
					(thickness 0.15)
				)
				(justify left bottom)
				(hide yes)
			)
		)
		(property "Footprint" "antmicro-footprints:R_0402_1005Metric"
			(at 156.21 130.81 0)
			(effects
				(font
					(size 1.27 1.27)
					(thickness 0.15)
				)
				(justify left bottom)
				(hide yes)
			)
		)
		(property "Datasheet" "https://industrial.panasonic.com/cdbs/www-data/pdf/RDA0000/AOA0000C301.pdf"
			(at 158.75 130.81 0)
			(effects
				(font
					(size 1.27 1.27)
					(thickness 0.15)
				)
				(justify left bottom)
				(hide yes)
			)
		)
		(property "Description" "SMD Chip Resistor, Jumper, 0 ohm, 100 mW, 0402 [1005 Metric], Thick Film, General Purpose"
			(at 140.97 151.13 0)
			(effects
				(font
					(size 1.27 1.27)
				)
				(hide yes)
			)
		)
		(property "Manufacturer" "Panasonic"
			(at 163.83 130.81 0)
			(effects
				(font
					(size 1.27 1.27)
					(thickness 0.15)
				)
				(justify left bottom)
				(hide yes)
			)
		)
		(property "MPN" "ERJ2GE0R00X"
			(at 161.29 130.81 0)
			(effects
				(font
					(size 1.27 1.27)
					(thickness 0.15)
				)
				(justify left bottom)
				(hide yes)
			)
		)
		(property "Val" "0R"
			(at 142.24 149.86 90)
			(effects
				(font
					(size 1.27 1.27)
					(thickness 0.15)
				)
				(justify right)
			)
		)
		(property "License" "Apache-2.0"
			(at 166.37 130.81 0)
			(effects
				(font
					(size 1.27 1.27)
					(thickness 0.15)
				)
				(justify left bottom)
				(hide yes)
			)
		)
		(property "Author" "Antmicro"
			(at 168.91 130.81 0)
			(effects
				(font
					(size 1.27 1.27)
					(thickness 0.15)
				)
				(justify left bottom)
				(hide yes)
			)
		)
		(property "Tolerance" "~"
			(at 151.13 130.81 0)
			(effects
				(font
					(size 1.27 1.27)
				)
				(justify left bottom)
				(hide yes)
			)
		)
		(property "Current" "1A"
			(at 171.45 130.81 0)
			(effects
				(font
					(size 1.27 1.27)
					(thickness 0.15)
				)
				(justify left bottom)
				(hide yes)
			)
		)
		(pin "1"
		)
		(pin "2"
		)
		(instances
			(project "artix-dc-scm"
				(path ""
					(reference "R82")
					(unit 1)
				)
			)
		)
	)
	(symbol
		(lib_id "antmicroCapacitors0402:C_470n_0402")
		(at 259.08 50.8 90)
		(unit 1)
		(exclude_from_sim no)
		(in_bom yes)
		(on_board yes)
		(dnp no)
		(property "Reference" "C115"
			(at 259.715 46.355 90)
			(effects
				(font
					(size 1.27 1.27)
				)
				(justify right)
			)
		)
		(property "Value" "C_470n_0402"
			(at 269.24 30.48 0)
			(effects
				(font
					(size 1.27 1.27)
					(thickness 0.15)
				)
				(justify left bottom)
				(hide yes)
			)
		)
		(property "Footprint" "antmicro-footprints:C_0402_1005Metric"
			(at 271.78 30.48 0)
			(effects
				(font
					(size 1.27 1.27)
					(thickness 0.15)
				)
				(justify left bottom)
				(hide yes)
			)
		)
		(property "Datasheet" "https://product.tdk.com/en/search/capacitor/ceramic/mlcc/info?part_no=C1005X5R1E474M050BB"
			(at 274.32 30.48 0)
			(effects
				(font
					(size 1.27 1.27)
					(thickness 0.15)
				)
				(justify left bottom)
				(hide yes)
			)
		)
		(property "Description" "SMD Multilayer Ceramic Capacitor, 0.47 µF, 25 V, 0402 [1005 Metric], ± 20%, X5R, C"
			(at 259.08 50.8 0)
			(effects
				(font
					(size 1.27 1.27)
				)
				(hide yes)
			)
		)
		(property "Manufacturer" "TDK"
			(at 279.4 30.48 0)
			(effects
				(font
					(size 1.27 1.27)
					(thickness 0.15)
				)
				(justify left bottom)
				(hide yes)
			)
		)
		(property "MPN" "C1005X5R1E474M050BB"
			(at 276.86 30.48 0)
			(effects
				(font
					(size 1.27 1.27)
					(thickness 0.15)
				)
				(justify left bottom)
				(hide yes)
			)
		)
		(property "Val" "470n"
			(at 259.715 50.165 90)
			(effects
				(font
					(size 1.27 1.27)
					(thickness 0.15)
				)
				(justify right)
			)
		)
		(property "License" "Apache-2.0"
			(at 281.94 30.48 0)
			(effects
				(font
					(size 1.27 1.27)
					(thickness 0.15)
				)
				(justify left bottom)
				(hide yes)
			)
		)
		(property "Author" "Antmicro"
			(at 284.48 30.48 0)
			(effects
				(font
					(size 1.27 1.27)
					(thickness 0.15)
				)
				(justify left bottom)
				(hide yes)
			)
		)
		(property "Voltage" ""
			(at 287.02 30.48 0)
			(effects
				(font
					(size 1.27 1.27)
				)
				(justify left bottom)
				(hide yes)
			)
		)
		(property "Dielectric" ""
			(at 289.56 30.48 0)
			(effects
				(font
					(size 1.27 1.27)
				)
				(justify left bottom)
				(hide yes)
			)
		)
		(pin "1"
		)
		(pin "2"
		)
		(instances
			(project "artix-dc-scm"
				(path ""
					(reference "C115")
					(unit 1)
				)
			)
		)
	)
	(symbol
		(lib_id "antmicroCapacitors0402:C_470n_0402")
		(at 250.19 64.77 90)
		(unit 1)
		(exclude_from_sim no)
		(in_bom yes)
		(on_board yes)
		(dnp no)
		(property "Reference" "C237"
			(at 250.825 60.325 90)
			(effects
				(font
					(size 1.27 1.27)
				)
				(justify right)
			)
		)
		(property "Value" "C_470n_0402"
			(at 260.35 44.45 0)
			(effects
				(font
					(size 1.27 1.27)
					(thickness 0.15)
				)
				(justify left bottom)
				(hide yes)
			)
		)
		(property "Footprint" "antmicro-footprints:C_0402_1005Metric"
			(at 262.89 44.45 0)
			(effects
				(font
					(size 1.27 1.27)
					(thickness 0.15)
				)
				(justify left bottom)
				(hide yes)
			)
		)
		(property "Datasheet" "https://product.tdk.com/en/search/capacitor/ceramic/mlcc/info?part_no=C1005X5R1E474M050BB"
			(at 265.43 44.45 0)
			(effects
				(font
					(size 1.27 1.27)
					(thickness 0.15)
				)
				(justify left bottom)
				(hide yes)
			)
		)
		(property "Description" "SMD Multilayer Ceramic Capacitor, 0.47 µF, 25 V, 0402 [1005 Metric], ± 20%, X5R, C"
			(at 250.19 64.77 0)
			(effects
				(font
					(size 1.27 1.27)
				)
				(hide yes)
			)
		)
		(property "Manufacturer" "TDK"
			(at 270.51 44.45 0)
			(effects
				(font
					(size 1.27 1.27)
					(thickness 0.15)
				)
				(justify left bottom)
				(hide yes)
			)
		)
		(property "MPN" "C1005X5R1E474M050BB"
			(at 267.97 44.45 0)
			(effects
				(font
					(size 1.27 1.27)
					(thickness 0.15)
				)
				(justify left bottom)
				(hide yes)
			)
		)
		(property "Val" "470n"
			(at 250.825 64.135 90)
			(effects
				(font
					(size 1.27 1.27)
					(thickness 0.15)
				)
				(justify right)
			)
		)
		(property "License" "Apache-2.0"
			(at 273.05 44.45 0)
			(effects
				(font
					(size 1.27 1.27)
					(thickness 0.15)
				)
				(justify left bottom)
				(hide yes)
			)
		)
		(property "Author" "Antmicro"
			(at 275.59 44.45 0)
			(effects
				(font
					(size 1.27 1.27)
					(thickness 0.15)
				)
				(justify left bottom)
				(hide yes)
			)
		)
		(property "Voltage" ""
			(at 278.13 44.45 0)
			(effects
				(font
					(size 1.27 1.27)
				)
				(justify left bottom)
				(hide yes)
			)
		)
		(property "Dielectric" ""
			(at 280.67 44.45 0)
			(effects
				(font
					(size 1.27 1.27)
				)
				(justify left bottom)
				(hide yes)
			)
		)
		(pin "1"
		)
		(pin "2"
		)
		(instances
			(project "artix-dc-scm"
				(path ""
					(reference "C237")
					(unit 1)
				)
			)
		)
	)
	(symbol
		(lib_id "antmicroCapacitors0402:C_470n_0402")
		(at 340.36 50.8 270)
		(mirror x)
		(unit 1)
		(exclude_from_sim no)
		(in_bom yes)
		(on_board yes)
		(dnp no)
		(property "Reference" "C120"
			(at 339.09 46.355 90)
			(effects
				(font
					(size 1.27 1.27)
				)
				(justify right)
			)
		)
		(property "Value" "C_470n_0402"
			(at 330.2 30.48 0)
			(effects
				(font
					(size 1.27 1.27)
					(thickness 0.15)
				)
				(justify left bottom)
				(hide yes)
			)
		)
		(property "Footprint" "antmicro-footprints:C_0402_1005Metric"
			(at 327.66 30.48 0)
			(effects
				(font
					(size 1.27 1.27)
					(thickness 0.15)
				)
				(justify left bottom)
				(hide yes)
			)
		)
		(property "Datasheet" "https://product.tdk.com/en/search/capacitor/ceramic/mlcc/info?part_no=C1005X5R1E474M050BB"
			(at 325.12 30.48 0)
			(effects
				(font
					(size 1.27 1.27)
					(thickness 0.15)
				)
				(justify left bottom)
				(hide yes)
			)
		)
		(property "Description" "SMD Multilayer Ceramic Capacitor, 0.47 µF, 25 V, 0402 [1005 Metric], ± 20%, X5R, C"
			(at 340.36 50.8 0)
			(effects
				(font
					(size 1.27 1.27)
				)
				(hide yes)
			)
		)
		(property "Manufacturer" "TDK"
			(at 320.04 30.48 0)
			(effects
				(font
					(size 1.27 1.27)
					(thickness 0.15)
				)
				(justify left bottom)
				(hide yes)
			)
		)
		(property "MPN" "C1005X5R1E474M050BB"
			(at 322.58 30.48 0)
			(effects
				(font
					(size 1.27 1.27)
					(thickness 0.15)
				)
				(justify left bottom)
				(hide yes)
			)
		)
		(property "Val" "470n"
			(at 339.725 50.165 90)
			(effects
				(font
					(size 1.27 1.27)
					(thickness 0.15)
				)
				(justify right)
			)
		)
		(property "License" "Apache-2.0"
			(at 317.5 30.48 0)
			(effects
				(font
					(size 1.27 1.27)
					(thickness 0.15)
				)
				(justify left bottom)
				(hide yes)
			)
		)
		(property "Author" "Antmicro"
			(at 314.96 30.48 0)
			(effects
				(font
					(size 1.27 1.27)
					(thickness 0.15)
				)
				(justify left bottom)
				(hide yes)
			)
		)
		(property "Voltage" ""
			(at 312.42 30.48 0)
			(effects
				(font
					(size 1.27 1.27)
				)
				(justify left bottom)
				(hide yes)
			)
		)
		(property "Dielectric" ""
			(at 309.88 30.48 0)
			(effects
				(font
					(size 1.27 1.27)
				)
				(justify left bottom)
				(hide yes)
			)
		)
		(property "DNP" ""
			(at 340.36 50.8 0)
			(effects
				(font
					(size 1.27 1.27)
				)
			)
		)
		(pin "1"
		)
		(pin "2"
		)
		(instances
			(project "artix-dc-scm"
				(path ""
					(reference "C120")
					(unit 1)
				)
			)
		)
	)
	(symbol
		(lib_id "antmicroResistors0402:R_1k_0402")
		(at 73.66 260.35 0)
		(unit 1)
		(exclude_from_sim no)
		(in_bom yes)
		(on_board yes)
		(dnp no)
		(property "Reference" "R130"
			(at 76.2 257.175 0)
			(effects
				(font
					(size 1.27 1.27)
				)
			)
		)
		(property "Value" "R_1k_0402"
			(at 93.98 273.05 0)
			(effects
				(font
					(size 1.27 1.27)
					(thickness 0.15)
				)
				(justify left bottom)
				(hide yes)
			)
		)
		(property "Footprint" "antmicro-footprints:R_0402_1005Metric"
			(at 93.98 275.59 0)
			(effects
				(font
					(size 1.27 1.27)
					(thickness 0.15)
				)
				(justify left bottom)
				(hide yes)
			)
		)
		(property "Datasheet" "https://www.bourns.com/docs/product-datasheets/cr.pdf"
			(at 93.98 278.13 0)
			(effects
				(font
					(size 1.27 1.27)
					(thickness 0.15)
				)
				(justify left bottom)
				(hide yes)
			)
		)
		(property "Description" "SMD Chip Resistor, 1 kohm, ± 1%, 63 mW, 0402 [1005 Metric], Thick Film, General Purpose"
			(at 73.66 260.35 0)
			(effects
				(font
					(size 1.27 1.27)
				)
				(hide yes)
			)
		)
		(property "Manufacturer" "Bourns"
			(at 93.98 283.21 0)
			(effects
				(font
					(size 1.27 1.27)
					(thickness 0.15)
				)
				(justify left bottom)
				(hide yes)
			)
		)
		(property "MPN" "CR0402-FX-1001GLF"
			(at 93.98 280.67 0)
			(effects
				(font
					(size 1.27 1.27)
					(thickness 0.15)
				)
				(justify left bottom)
				(hide yes)
			)
		)
		(property "Val" "1k"
			(at 76.2 262.89 0)
			(effects
				(font
					(size 1.27 1.27)
					(thickness 0.15)
				)
			)
		)
		(property "License" "Apache-2.0"
			(at 93.98 285.75 0)
			(effects
				(font
					(size 1.27 1.27)
					(thickness 0.15)
				)
				(justify left bottom)
				(hide yes)
			)
		)
		(property "Author" "Antmicro"
			(at 93.98 288.29 0)
			(effects
				(font
					(size 1.27 1.27)
					(thickness 0.15)
				)
				(justify left bottom)
				(hide yes)
			)
		)
		(property "Tolerance" "1%"
			(at 93.98 270.51 0)
			(effects
				(font
					(size 1.27 1.27)
				)
				(justify left bottom)
				(hide yes)
			)
		)
		(pin "1"
		)
		(pin "2"
		)
		(instances
			(project "artix-dc-scm"
				(path ""
					(reference "R130")
					(unit 1)
				)
			)
		)
	)
	(symbol
		(lib_id "antmicropower:GND")
		(at 232.41 50.8 0)
		(unit 1)
		(exclude_from_sim no)
		(in_bom yes)
		(on_board yes)
		(dnp no)
		(property "Reference" "#PWR0319"
			(at 232.41 57.15 0)
			(effects
				(font
					(size 1.27 1.27)
				)
				(hide yes)
			)
		)
		(property "Value" "GND"
			(at 232.41 54.61 0)
			(effects
				(font
					(size 1.27 1.27)
				)
			)
		)
		(property "Footprint" ""
			(at 232.41 50.8 0)
			(effects
				(font
					(size 1.27 1.27)
				)
				(hide yes)
			)
		)
		(property "Datasheet" ""
			(at 232.41 50.8 0)
			(effects
				(font
					(size 1.27 1.27)
				)
				(hide yes)
			)
		)
		(property "Description" ""
			(at 232.41 50.8 0)
			(effects
				(font
					(size 1.27 1.27)
				)
				(hide yes)
			)
		)
		(property "Author" "Antmicro"
			(at 241.3 58.42 0)
			(effects
				(font
					(size 1.27 1.27)
					(thickness 0.15)
				)
				(justify left bottom)
				(hide yes)
			)
		)
		(property "License" "Apache-2.0"
			(at 241.3 60.96 0)
			(effects
				(font
					(size 1.27 1.27)
					(thickness 0.15)
				)
				(justify left bottom)
				(hide yes)
			)
		)
		(pin "1"
		)
		(instances
			(project "artix-dc-scm"
				(path ""
					(reference "#PWR0319")
					(unit 1)
				)
			)
		)
	)
	(symbol
		(lib_id "antmicroLEDIndicationDiscrete:LED_G_0603_LG_L29K-G2J1-24-Z")
		(at 154.94 228.6 0)
		(unit 1)
		(exclude_from_sim no)
		(in_bom yes)
		(on_board yes)
		(dnp no)
		(fields_autoplaced yes)
		(property "Reference" "D12"
			(at 157.48 218.44 0)
			(effects
				(font
					(size 1.27 1.27)
				)
			)
		)
		(property "Value" "LED_G_0603_LG_L29K-G2J1-24-Z"
			(at 158.75 223.52 0)
			(effects
				(font
					(size 1.27 1.27)
					(thickness 0.15)
				)
				(hide yes)
			)
		)
		(property "Footprint" "antmicro-footprints:LED_0603_1608Metric_G"
			(at 177.8 238.76 0)
			(effects
				(font
					(size 1.27 1.27)
					(thickness 0.15)
				)
				(justify left bottom)
				(hide yes)
			)
		)
		(property "Datasheet" "https://look.ams-osram.com/m/19ee86b3ae0ee95b/original/LG-L29K.pdf"
			(at 177.8 241.3 0)
			(effects
				(font
					(size 1.27 1.27)
					(thickness 0.15)
				)
				(justify left bottom)
				(hide yes)
			)
		)
		(property "Description" "LED, Green, SMD, 0603, 20 mA, 1.7 V, 570 nm"
			(at 154.94 228.6 0)
			(effects
				(font
					(size 1.27 1.27)
				)
				(hide yes)
			)
		)
		(property "MPN" "LG L29K-G2J1-24-Z"
			(at 157.48 220.98 0)
			(effects
				(font
					(size 1.27 1.27)
					(thickness 0.15)
				)
			)
		)
		(property "Manufacturer" "OSRAM"
			(at 177.8 246.38 0)
			(effects
				(font
					(size 1.27 1.27)
					(thickness 0.15)
				)
				(justify left bottom)
				(hide yes)
			)
		)
		(property "Author" "Antmicro"
			(at 177.8 248.92 0)
			(effects
				(font
					(size 1.27 1.27)
					(thickness 0.15)
				)
				(justify left bottom)
				(hide yes)
			)
		)
		(property "License" "Apache-2.0"
			(at 177.8 251.46 0)
			(effects
				(font
					(size 1.27 1.27)
					(thickness 0.15)
				)
				(justify left bottom)
				(hide yes)
			)
		)
		(property "Color" "Green"
			(at 157.48 223.52 0)
			(effects
				(font
					(size 1.27 1.27)
				)
			)
		)
		(pin "1"
		)
		(pin "2"
		)
		(instances
			(project "artix-dc-scm"
				(path ""
					(reference "D12")
					(unit 1)
				)
			)
		)
	)
	(symbol
		(lib_id "antmicroGenericPinHeaders:PinHeader_1x3_P2.54mm_Drill1.1mm")
		(at 107.95 142.24 0)
		(mirror y)
		(unit 1)
		(exclude_from_sim no)
		(in_bom yes)
		(on_board yes)
		(dnp no)
		(fields_autoplaced yes)
		(property "Reference" "J13"
			(at 101.6 143.51 0)
			(effects
				(font
					(size 1.27 1.27)
				)
				(justify left)
			)
		)
		(property "Value" "PinHeader_1x3_P2.54mm_Drill1.1mm"
			(at 87.63 152.4 0)
			(effects
				(font
					(size 1.27 1.27)
					(thickness 0.15)
				)
				(justify left bottom)
				(hide yes)
			)
		)
		(property "Footprint" "antmicro-footprints:PinHeader_1x3_P2.54mm_Drill1.1mm"
			(at 87.63 154.94 0)
			(effects
				(font
					(size 1.27 1.27)
					(thickness 0.15)
				)
				(justify left bottom)
				(hide yes)
			)
		)
		(property "Datasheet" "https://katalog.we-online.de/em/datasheet/6130xx11121.pdf"
			(at 87.63 157.48 0)
			(effects
				(font
					(size 1.27 1.27)
					(thickness 0.15)
				)
				(justify left bottom)
				(hide yes)
			)
		)
		(property "Description" "Pin Header, Vertical, Board-to-Board, 2.54 mm, 1 Rows, 3 Contacts, Through Hole Straight, WR-PHD"
			(at 107.95 142.24 0)
			(effects
				(font
					(size 1.27 1.27)
				)
				(hide yes)
			)
		)
		(property "MPN" "61300311121"
			(at 101.6 146.05 0)
			(effects
				(font
					(size 1.27 1.27)
					(thickness 0.15)
				)
				(justify left)
			)
		)
		(property "Manufacturer" "Würth Elektronik"
			(at 87.63 160.02 0)
			(effects
				(font
					(size 1.27 1.27)
					(thickness 0.15)
				)
				(justify left bottom)
				(hide yes)
			)
		)
		(property "Author" "Antmicro"
			(at 87.63 165.1 0)
			(effects
				(font
					(size 1.27 1.27)
					(thickness 0.15)
				)
				(justify left bottom)
				(hide yes)
			)
		)
		(property "License" "Apache-2.0"
			(at 87.63 167.64 0)
			(effects
				(font
					(size 1.27 1.27)
					(thickness 0.15)
				)
				(justify left bottom)
				(hide yes)
			)
		)
		(property "VSD_class" "IO Header"
			(at 87.63 162.56 0)
			(effects
				(font
					(size 1.27 1.27)
					(thickness 0.15)
				)
				(justify left bottom)
				(hide yes)
			)
		)
		(pin "1"
		)
		(pin "2"
		)
		(pin "3"
		)
		(instances
			(project "artix-dc-scm"
				(path ""
					(reference "J13")
					(unit 1)
				)
			)
		)
	)
	(symbol
		(lib_id "antmicropower:GND")
		(at 340.36 63.5 0)
		(mirror y)
		(unit 1)
		(exclude_from_sim no)
		(in_bom yes)
		(on_board yes)
		(dnp no)
		(property "Reference" "#PWR060"
			(at 340.36 69.85 0)
			(effects
				(font
					(size 1.27 1.27)
				)
				(hide yes)
			)
		)
		(property "Value" "GND"
			(at 340.36 67.31 0)
			(effects
				(font
					(size 1.27 1.27)
				)
			)
		)
		(property "Footprint" ""
			(at 340.36 63.5 0)
			(effects
				(font
					(size 1.27 1.27)
				)
				(hide yes)
			)
		)
		(property "Datasheet" ""
			(at 340.36 63.5 0)
			(effects
				(font
					(size 1.27 1.27)
				)
				(hide yes)
			)
		)
		(property "Description" ""
			(at 340.36 63.5 0)
			(effects
				(font
					(size 1.27 1.27)
				)
				(hide yes)
			)
		)
		(property "Author" "Antmicro"
			(at 331.47 71.12 0)
			(effects
				(font
					(size 1.27 1.27)
					(thickness 0.15)
				)
				(justify left bottom)
				(hide yes)
			)
		)
		(property "License" "Apache-2.0"
			(at 331.47 73.66 0)
			(effects
				(font
					(size 1.27 1.27)
					(thickness 0.15)
				)
				(justify left bottom)
				(hide yes)
			)
		)
		(pin "1"
		)
		(instances
			(project "artix-dc-scm"
				(path ""
					(reference "#PWR060")
					(unit 1)
				)
			)
		)
	)
	(symbol
		(lib_id "antmicroFPGAChips:XC7A100T-FGG484")
		(at 62.23 78.74 0)
		(mirror y)
		(unit 4)
		(exclude_from_sim no)
		(in_bom yes)
		(on_board yes)
		(dnp no)
		(fields_autoplaced yes)
		(property "Reference" "U14"
			(at 48.895 71.12 0)
			(effects
				(font
					(size 1.27 1.27)
				)
			)
		)
		(property "Value" "XC7A100T-FGG484"
			(at 48.895 73.66 0)
			(effects
				(font
					(size 1.27 1.27)
				)
			)
		)
		(property "Footprint" "antmicro-footprints:BGA-484_23x23mm_Layout22x22_P1mm_FGG484"
			(at 6.35 86.36 0)
			(effects
				(font
					(size 1.27 1.27)
					(thickness 0.15)
				)
				(justify left bottom)
				(hide yes)
			)
		)
		(property "Datasheet" "https://docs.xilinx.com/v/u/en-US/ds181_Artix_7_Data_Sheet"
			(at 6.35 88.9 0)
			(effects
				(font
					(size 1.27 1.27)
					(thickness 0.15)
				)
				(justify left bottom)
				(hide yes)
			)
		)
		(property "Description" "Artix-7 Field Programmable Gate Array IC 210 324-LFBGA, CSPBGA"
			(at 62.23 78.74 0)
			(effects
				(font
					(size 1.27 1.27)
				)
				(hide yes)
			)
		)
		(property "MPN" "XC7A100T-FGG484"
			(at 6.35 91.44 0)
			(effects
				(font
					(size 1.27 1.27)
					(thickness 0.15)
				)
				(justify left bottom)
				(hide yes)
			)
		)
		(property "Manufacturer" "AMD-Xilinx"
			(at 6.35 93.98 0)
			(effects
				(font
					(size 1.27 1.27)
					(thickness 0.15)
				)
				(justify left bottom)
				(hide yes)
			)
		)
		(property "Author" "Antmicro"
			(at 6.35 96.52 0)
			(effects
				(font
					(size 1.27 1.27)
					(thickness 0.15)
				)
				(justify left bottom)
				(hide yes)
			)
		)
		(property "License" "Apache-2.0"
			(at 6.35 99.06 0)
			(effects
				(font
					(size 1.27 1.27)
					(thickness 0.15)
				)
				(justify left bottom)
				(hide yes)
			)
		)
		(pin "AA10"
		)
		(pin "AA11"
		)
		(pin "AA13"
		)
		(pin "AA14"
		)
		(pin "AA15"
		)
		(pin "AA16"
		)
		(pin "AA17"
		)
		(pin "AA9"
		)
		(pin "AB10"
		)
		(pin "AB11"
		)
		(pin "AB12"
		)
		(pin "AB13"
		)
		(pin "AB14"
		)
		(pin "AB15"
		)
		(pin "AB16"
		)
		(pin "AB17"
		)
		(pin "T14"
		)
		(pin "T15"
		)
		(pin "T16"
		)
		(pin "U15"
		)
		(pin "U16"
		)
		(pin "V10"
		)
		(pin "V13"
		)
		(pin "V14"
		)
		(pin "V15"
		)
		(pin "V16"
		)
		(pin "W10"
		)
		(pin "W11"
		)
		(pin "W12"
		)
		(pin "W13"
		)
		(pin "W14"
		)
		(pin "W15"
		)
		(pin "W16"
		)
		(pin "Y10"
		)
		(pin "Y11"
		)
		(pin "Y12"
		)
		(pin "Y13"
		)
		(pin "Y14"
		)
		(pin "Y16"
		)
		(pin "Y17"
		)
		(pin "AA18"
		)
		(pin "AA19"
		)
		(pin "AA20"
		)
		(pin "AA21"
		)
		(pin "AB18"
		)
		(pin "AB20"
		)
		(pin "AB21"
		)
		(pin "AB22"
		)
		(pin "M14"
		)
		(pin "N13"
		)
		(pin "N14"
		)
		(pin "N15"
		)
		(pin "N17"
		)
		(pin "P14"
		)
		(pin "P15"
		)
		(pin "P16"
		)
		(pin "P17"
		)
		(pin "P18"
		)
		(pin "P19"
		)
		(pin "P20"
		)
		(pin "P21"
		)
		(pin "P22"
		)
		(pin "R14"
		)
		(pin "R15"
		)
		(pin "R16"
		)
		(pin "R17"
		)
		(pin "R18"
		)
		(pin "R19"
		)
		(pin "R21"
		)
		(pin "R22"
		)
		(pin "T18"
		)
		(pin "T19"
		)
		(pin "T20"
		)
		(pin "T21"
		)
		(pin "T22"
		)
		(pin "U17"
		)
		(pin "U18"
		)
		(pin "U19"
		)
		(pin "U20"
		)
		(pin "U21"
		)
		(pin "U22"
		)
		(pin "V17"
		)
		(pin "V18"
		)
		(pin "V19"
		)
		(pin "V20"
		)
		(pin "V22"
		)
		(pin "W17"
		)
		(pin "W19"
		)
		(pin "W20"
		)
		(pin "W21"
		)
		(pin "W22"
		)
		(pin "Y18"
		)
		(pin "Y19"
		)
		(pin "Y20"
		)
		(pin "Y21"
		)
		(pin "Y22"
		)
		(pin "G13"
		)
		(pin "G15"
		)
		(pin "G16"
		)
		(pin "G17"
		)
		(pin "G18"
		)
		(pin "G19"
		)
		(pin "G20"
		)
		(pin "H13"
		)
		(pin "H14"
		)
		(pin "H15"
		)
		(pin "H16"
		)
		(pin "H17"
		)
		(pin "H18"
		)
		(pin "H19"
		)
		(pin "H20"
		)
		(pin "H22"
		)
		(pin "J13"
		)
		(pin "J14"
		)
		(pin "J15"
		)
		(pin "J16"
		)
		(pin "J17"
		)
		(pin "J19"
		)
		(pin "J20"
		)
		(pin "J21"
		)
		(pin "J22"
		)
		(pin "K13"
		)
		(pin "K14"
		)
		(pin "K16"
		)
		(pin "K17"
		)
		(pin "K18"
		)
		(pin "K19"
		)
		(pin "K20"
		)
		(pin "K21"
		)
		(pin "K22"
		)
		(pin "L13"
		)
		(pin "L14"
		)
		(pin "L15"
		)
		(pin "L16"
		)
		(pin "L17"
		)
		(pin "L18"
		)
		(pin "L19"
		)
		(pin "L20"
		)
		(pin "L21"
		)
		(pin "M13"
		)
		(pin "M15"
		)
		(pin "M16"
		)
		(pin "M17"
		)
		(pin "M18"
		)
		(pin "M20"
		)
		(pin "M21"
		)
		(pin "M22"
		)
		(pin "N18"
		)
		(pin "N19"
		)
		(pin "N20"
		)
		(pin "N21"
		)
		(pin "N22"
		)
		(pin "A13"
		)
		(pin "A14"
		)
		(pin "A15"
		)
		(pin "A16"
		)
		(pin "A17"
		)
		(pin "A18"
		)
		(pin "A19"
		)
		(pin "A20"
		)
		(pin "A21"
		)
		(pin "B13"
		)
		(pin "B14"
		)
		(pin "B15"
		)
		(pin "B16"
		)
		(pin "B17"
		)
		(pin "B18"
		)
		(pin "B20"
		)
		(pin "B21"
		)
		(pin "B22"
		)
		(pin "C13"
		)
		(pin "C14"
		)
		(pin "C15"
		)
		(pin "C17"
		)
		(pin "C18"
		)
		(pin "C19"
		)
		(pin "C20"
		)
		(pin "C21"
		)
		(pin "C22"
		)
		(pin "D14"
		)
		(pin "D15"
		)
		(pin "D16"
		)
		(pin "D17"
		)
		(pin "D18"
		)
		(pin "D19"
		)
		(pin "D20"
		)
		(pin "D21"
		)
		(pin "D22"
		)
		(pin "E13"
		)
		(pin "E14"
		)
		(pin "E15"
		)
		(pin "E16"
		)
		(pin "E17"
		)
		(pin "E18"
		)
		(pin "E19"
		)
		(pin "E21"
		)
		(pin "E22"
		)
		(pin "F13"
		)
		(pin "F14"
		)
		(pin "F15"
		)
		(pin "F16"
		)
		(pin "F18"
		)
		(pin "F19"
		)
		(pin "F20"
		)
		(pin "F21"
		)
		(pin "F22"
		)
		(pin "G21"
		)
		(pin "G22"
		)
		(pin "AA1"
		)
		(pin "AA3"
		)
		(pin "AA4"
		)
		(pin "AA5"
		)
		(pin "AA6"
		)
		(pin "AA7"
		)
		(pin "AA8"
		)
		(pin "AB1"
		)
		(pin "AB2"
		)
		(pin "AB3"
		)
		(pin "AB4"
		)
		(pin "AB5"
		)
		(pin "AB6"
		)
		(pin "AB7"
		)
		(pin "AB8"
		)
		(pin "R2"
		)
		(pin "R3"
		)
		(pin "R4"
		)
		(pin "R5"
		)
		(pin "R6"
		)
		(pin "T1"
		)
		(pin "T2"
		)
		(pin "T3"
		)
		(pin "T4"
		)
		(pin "T5"
		)
		(pin "T6"
		)
		(pin "U1"
		)
		(pin "U2"
		)
		(pin "U3"
		)
		(pin "U5"
		)
		(pin "U6"
		)
		(pin "U7"
		)
		(pin "V2"
		)
		(pin "V3"
		)
		(pin "V4"
		)
		(pin "V5"
		)
		(pin "V6"
		)
		(pin "V7"
		)
		(pin "V8"
		)
		(pin "V9"
		)
		(pin "W1"
		)
		(pin "W2"
		)
		(pin "W3"
		)
		(pin "W4"
		)
		(pin "W5"
		)
		(pin "W6"
		)
		(pin "W7"
		)
		(pin "W9"
		)
		(pin "Y1"
		)
		(pin "Y2"
		)
		(pin "Y3"
		)
		(pin "Y4"
		)
		(pin "Y6"
		)
		(pin "Y7"
		)
		(pin "Y8"
		)
		(pin "Y9"
		)
		(pin "A1"
		)
		(pin "B1"
		)
		(pin "B2"
		)
		(pin "C1"
		)
		(pin "C2"
		)
		(pin "D1"
		)
		(pin "D2"
		)
		(pin "E1"
		)
		(pin "E2"
		)
		(pin "E3"
		)
		(pin "F1"
		)
		(pin "F2"
		)
		(pin "F3"
		)
		(pin "F4"
		)
		(pin "G1"
		)
		(pin "G2"
		)
		(pin "G3"
		)
		(pin "G4"
		)
		(pin "H2"
		)
		(pin "H3"
		)
		(pin "H4"
		)
		(pin "H5"
		)
		(pin "H6"
		)
		(pin "J1"
		)
		(pin "J2"
		)
		(pin "J3"
		)
		(pin "J4"
		)
		(pin "J5"
		)
		(pin "J6"
		)
		(pin "K1"
		)
		(pin "K2"
		)
		(pin "K3"
		)
		(pin "K4"
		)
		(pin "K6"
		)
		(pin "L1"
		)
		(pin "L3"
		)
		(pin "L4"
		)
		(pin "L5"
		)
		(pin "L6"
		)
		(pin "M1"
		)
		(pin "M2"
		)
		(pin "M3"
		)
		(pin "M4"
		)
		(pin "M5"
		)
		(pin "M6"
		)
		(pin "N1"
		)
		(pin "N2"
		)
		(pin "N3"
		)
		(pin "N4"
		)
		(pin "N5"
		)
		(pin "P1"
		)
		(pin "P2"
		)
		(pin "P4"
		)
		(pin "P5"
		)
		(pin "P6"
		)
		(pin "R1"
		)
		(pin "F12"
		)
		(pin "G11"
		)
		(pin "L10"
		)
		(pin "L12"
		)
		(pin "L9"
		)
		(pin "M10"
		)
		(pin "M9"
		)
		(pin "N10"
		)
		(pin "N12"
		)
		(pin "N9"
		)
		(pin "R13"
		)
		(pin "T12"
		)
		(pin "T13"
		)
		(pin "U10"
		)
		(pin "U11"
		)
		(pin "U12"
		)
		(pin "U13"
		)
		(pin "U8"
		)
		(pin "U9"
		)
		(pin "V12"
		)
		(pin "A10"
		)
		(pin "A4"
		)
		(pin "A6"
		)
		(pin "A8"
		)
		(pin "B10"
		)
		(pin "B11"
		)
		(pin "B4"
		)
		(pin "B5"
		)
		(pin "B6"
		)
		(pin "B7"
		)
		(pin "B8"
		)
		(pin "B9"
		)
		(pin "C11"
		)
		(pin "C4"
		)
		(pin "C5"
		)
		(pin "C7"
		)
		(pin "C8"
		)
		(pin "C9"
		)
		(pin "D10"
		)
		(pin "D11"
		)
		(pin "D5"
		)
		(pin "D6"
		)
		(pin "D7"
		)
		(pin "D9"
		)
		(pin "E10"
		)
		(pin "E6"
		)
		(pin "E8"
		)
		(pin "F10"
		)
		(pin "F6"
		)
		(pin "F7"
		)
		(pin "F8"
		)
		(pin "F9"
		)
		(pin "A11"
		)
		(pin "A12"
		)
		(pin "A2"
		)
		(pin "A22"
		)
		(pin "A3"
		)
		(pin "A5"
		)
		(pin "A7"
		)
		(pin "A9"
		)
		(pin "AA12"
		)
		(pin "AA2"
		)
		(pin "AA22"
		)
		(pin "AB19"
		)
		(pin "AB9"
		)
		(pin "B12"
		)
		(pin "B19"
		)
		(pin "B3"
		)
		(pin "C10"
		)
		(pin "C12"
		)
		(pin "C16"
		)
		(pin "C3"
		)
		(pin "C6"
		)
		(pin "D12"
		)
		(pin "D13"
		)
		(pin "D3"
		)
		(pin "D4"
		)
		(pin "D8"
		)
		(pin "E11"
		)
		(pin "E12"
		)
		(pin "E20"
		)
		(pin "E4"
		)
		(pin "E5"
		)
		(pin "E7"
		)
		(pin "E9"
		)
		(pin "F11"
		)
		(pin "F17"
		)
		(pin "F5"
		)
		(pin "G10"
		)
		(pin "G12"
		)
		(pin "G14"
		)
		(pin "G5"
		)
		(pin "G6"
		)
		(pin "G7"
		)
		(pin "G8"
		)
		(pin "G9"
		)
		(pin "H1"
		)
		(pin "H10"
		)
		(pin "H11"
		)
		(pin "H12"
		)
		(pin "H21"
		)
		(pin "H7"
		)
		(pin "H8"
		)
		(pin "H9"
		)
		(pin "J10"
		)
		(pin "J11"
		)
		(pin "J12"
		)
		(pin "J18"
		)
		(pin "J7"
		)
		(pin "J8"
		)
		(pin "J9"
		)
		(pin "K10"
		)
		(pin "K11"
		)
		(pin "K12"
		)
		(pin "K15"
		)
		(pin "K5"
		)
		(pin "K7"
		)
		(pin "K8"
		)
		(pin "K9"
		)
		(pin "L11"
		)
		(pin "L2"
		)
		(pin "L22"
		)
		(pin "L7"
		)
		(pin "L8"
		)
		(pin "M11"
		)
		(pin "M12"
		)
		(pin "M19"
		)
		(pin "M7"
		)
		(pin "M8"
		)
		(pin "N11"
		)
		(pin "N16"
		)
		(pin "N6"
		)
		(pin "N7"
		)
		(pin "N8"
		)
		(pin "P10"
		)
		(pin "P11"
		)
		(pin "P12"
		)
		(pin "P13"
		)
		(pin "P3"
		)
		(pin "P7"
		)
		(pin "P8"
		)
		(pin "P9"
		)
		(pin "R10"
		)
		(pin "R11"
		)
		(pin "R12"
		)
		(pin "R20"
		)
		(pin "R7"
		)
		(pin "R8"
		)
		(pin "R9"
		)
		(pin "T10"
		)
		(pin "T11"
		)
		(pin "T17"
		)
		(pin "T7"
		)
		(pin "T8"
		)
		(pin "T9"
		)
		(pin "U14"
		)
		(pin "U4"
		)
		(pin "V1"
		)
		(pin "V11"
		)
		(pin "V21"
		)
		(pin "W18"
		)
		(pin "W8"
		)
		(pin "Y15"
		)
		(pin "Y5"
		)
		(instances
			(project "artix-dc-scm"
				(path ""
					(reference "U14")
					(unit 4)
				)
			)
		)
	)
	(symbol
		(lib_id "antmicroPushbuttonSwitches:SW_KMR211NGLFS_SMD")
		(at 120.65 104.14 270)
		(unit 1)
		(exclude_from_sim no)
		(in_bom yes)
		(on_board yes)
		(dnp no)
		(fields_autoplaced yes)
		(property "Reference" "PROG_B1"
			(at 124.46 107.9499 90)
			(effects
				(font
					(size 1.27 1.27)
				)
				(justify left)
			)
		)
		(property "Value" "SW_KMR211NGLFS_SMD"
			(at 124.46 110.4899 90)
			(effects
				(font
					(size 1.27 1.27)
					(thickness 0.15)
				)
				(justify left)
				(hide yes)
			)
		)
		(property "Footprint" "antmicro-footprints:SW_KMR211NGLFS_SMD"
			(at 113.03 129.54 0)
			(effects
				(font
					(size 1.27 1.27)
					(thickness 0.15)
				)
				(justify left bottom)
				(hide yes)
			)
		)
		(property "Datasheet" "http://www.farnell.com/datasheets/2631211.pdf"
			(at 110.49 129.54 0)
			(effects
				(font
					(size 1.27 1.27)
					(thickness 0.15)
				)
				(justify left bottom)
				(hide yes)
			)
		)
		(property "Description" "Tactile Switch, KMR 2 Series, Top Actuated, Surface Mount, Oval Button, 120 gf, 50mA at 32VDC"
			(at 120.65 104.14 0)
			(effects
				(font
					(size 1.27 1.27)
				)
				(hide yes)
			)
		)
		(property "MPN" "KMR211NGLFS"
			(at 124.46 110.4899 90)
			(effects
				(font
					(size 1.27 1.27)
					(thickness 0.15)
				)
				(justify left)
			)
		)
		(property "Manufacturer" "C&K"
			(at 105.41 129.54 0)
			(effects
				(font
					(size 1.27 1.27)
					(thickness 0.15)
				)
				(justify left bottom)
				(hide yes)
			)
		)
		(property "Author" "Antmicro"
			(at 102.87 129.54 0)
			(effects
				(font
					(size 1.27 1.27)
					(thickness 0.15)
				)
				(justify left bottom)
				(hide yes)
			)
		)
		(property "License" "Apache-2.0"
			(at 100.33 129.54 0)
			(effects
				(font
					(size 1.27 1.27)
					(thickness 0.15)
				)
				(justify left bottom)
				(hide yes)
			)
		)
		(pin "1"
		)
		(pin "2"
		)
		(pin "3"
		)
		(pin "4"
		)
		(instances
			(project "artix-dc-scm"
				(path ""
					(reference "PROG_B1")
					(unit 1)
				)
			)
		)
	)
	(symbol
		(lib_id "antmicroCapacitors0402:C_470n_0402")
		(at 250.19 50.8 90)
		(unit 1)
		(exclude_from_sim no)
		(in_bom yes)
		(on_board yes)
		(dnp no)
		(property "Reference" "C109"
			(at 250.825 46.355 90)
			(effects
				(font
					(size 1.27 1.27)
				)
				(justify right)
			)
		)
		(property "Value" "C_470n_0402"
			(at 260.35 30.48 0)
			(effects
				(font
					(size 1.27 1.27)
					(thickness 0.15)
				)
				(justify left bottom)
				(hide yes)
			)
		)
		(property "Footprint" "antmicro-footprints:C_0402_1005Metric"
			(at 262.89 30.48 0)
			(effects
				(font
					(size 1.27 1.27)
					(thickness 0.15)
				)
				(justify left bottom)
				(hide yes)
			)
		)
		(property "Datasheet" "https://product.tdk.com/en/search/capacitor/ceramic/mlcc/info?part_no=C1005X5R1E474M050BB"
			(at 265.43 30.48 0)
			(effects
				(font
					(size 1.27 1.27)
					(thickness 0.15)
				)
				(justify left bottom)
				(hide yes)
			)
		)
		(property "Description" "SMD Multilayer Ceramic Capacitor, 0.47 µF, 25 V, 0402 [1005 Metric], ± 20%, X5R, C"
			(at 250.19 50.8 0)
			(effects
				(font
					(size 1.27 1.27)
				)
				(hide yes)
			)
		)
		(property "Manufacturer" "TDK"
			(at 270.51 30.48 0)
			(effects
				(font
					(size 1.27 1.27)
					(thickness 0.15)
				)
				(justify left bottom)
				(hide yes)
			)
		)
		(property "MPN" "C1005X5R1E474M050BB"
			(at 267.97 30.48 0)
			(effects
				(font
					(size 1.27 1.27)
					(thickness 0.15)
				)
				(justify left bottom)
				(hide yes)
			)
		)
		(property "Val" "470n"
			(at 250.825 50.165 90)
			(effects
				(font
					(size 1.27 1.27)
					(thickness 0.15)
				)
				(justify right)
			)
		)
		(property "License" "Apache-2.0"
			(at 273.05 30.48 0)
			(effects
				(font
					(size 1.27 1.27)
					(thickness 0.15)
				)
				(justify left bottom)
				(hide yes)
			)
		)
		(property "Author" "Antmicro"
			(at 275.59 30.48 0)
			(effects
				(font
					(size 1.27 1.27)
					(thickness 0.15)
				)
				(justify left bottom)
				(hide yes)
			)
		)
		(property "Voltage" ""
			(at 278.13 30.48 0)
			(effects
				(font
					(size 1.27 1.27)
				)
				(justify left bottom)
				(hide yes)
			)
		)
		(property "Dielectric" ""
			(at 280.67 30.48 0)
			(effects
				(font
					(size 1.27 1.27)
				)
				(justify left bottom)
				(hide yes)
			)
		)
		(pin "1"
		)
		(pin "2"
		)
		(instances
			(project "artix-dc-scm"
				(path ""
					(reference "C109")
					(unit 1)
				)
			)
		)
	)
	(symbol
		(lib_id "antmicroResistors0402:R_1k_0402")
		(at 168.91 260.35 0)
		(unit 1)
		(exclude_from_sim no)
		(in_bom yes)
		(on_board yes)
		(dnp no)
		(property "Reference" "R132"
			(at 171.45 257.81 0)
			(effects
				(font
					(size 1.27 1.27)
				)
			)
		)
		(property "Value" "R_1k_0402"
			(at 189.23 273.05 0)
			(effects
				(font
					(size 1.27 1.27)
					(thickness 0.15)
				)
				(justify left bottom)
				(hide yes)
			)
		)
		(property "Footprint" "antmicro-footprints:R_0402_1005Metric"
			(at 189.23 275.59 0)
			(effects
				(font
					(size 1.27 1.27)
					(thickness 0.15)
				)
				(justify left bottom)
				(hide yes)
			)
		)
		(property "Datasheet" "https://www.bourns.com/docs/product-datasheets/cr.pdf"
			(at 189.23 278.13 0)
			(effects
				(font
					(size 1.27 1.27)
					(thickness 0.15)
				)
				(justify left bottom)
				(hide yes)
			)
		)
		(property "Description" "SMD Chip Resistor, 1 kohm, ± 1%, 63 mW, 0402 [1005 Metric], Thick Film, General Purpose"
			(at 168.91 260.35 0)
			(effects
				(font
					(size 1.27 1.27)
				)
				(hide yes)
			)
		)
		(property "Manufacturer" "Bourns"
			(at 189.23 283.21 0)
			(effects
				(font
					(size 1.27 1.27)
					(thickness 0.15)
				)
				(justify left bottom)
				(hide yes)
			)
		)
		(property "MPN" "CR0402-FX-1001GLF"
			(at 189.23 280.67 0)
			(effects
				(font
					(size 1.27 1.27)
					(thickness 0.15)
				)
				(justify left bottom)
				(hide yes)
			)
		)
		(property "Val" "1k"
			(at 171.45 262.89 0)
			(effects
				(font
					(size 1.27 1.27)
					(thickness 0.15)
				)
			)
		)
		(property "License" "Apache-2.0"
			(at 189.23 285.75 0)
			(effects
				(font
					(size 1.27 1.27)
					(thickness 0.15)
				)
				(justify left bottom)
				(hide yes)
			)
		)
		(property "Author" "Antmicro"
			(at 189.23 288.29 0)
			(effects
				(font
					(size 1.27 1.27)
					(thickness 0.15)
				)
				(justify left bottom)
				(hide yes)
			)
		)
		(property "Tolerance" "1%"
			(at 189.23 270.51 0)
			(effects
				(font
					(size 1.27 1.27)
				)
				(justify left bottom)
				(hide yes)
			)
		)
		(pin "1"
		)
		(pin "2"
		)
		(instances
			(project "artix-dc-scm"
				(path ""
					(reference "R132")
					(unit 1)
				)
			)
		)
	)
	(symbol
		(lib_id "antmicroTransistorsFETsMOSFETsSingle:2N7002_SOT-23-3")
		(at 43.18 270.51 0)
		(unit 1)
		(exclude_from_sim no)
		(in_bom yes)
		(on_board yes)
		(dnp no)
		(fields_autoplaced yes)
		(property "Reference" "Q14"
			(at 54.61 266.6999 0)
			(effects
				(font
					(size 1.27 1.27)
				)
				(justify left)
			)
		)
		(property "Value" "2N7002_SOT-23-3"
			(at 54.61 269.2399 0)
			(effects
				(font
					(size 1.27 1.27)
					(thickness 0.15)
				)
				(justify left)
				(hide yes)
			)
		)
		(property "Footprint" "antmicro-footprints:SOT-23-3"
			(at 66.04 280.67 0)
			(effects
				(font
					(size 1.27 1.27)
					(thickness 0.15)
				)
				(justify left bottom)
				(hide yes)
			)
		)
		(property "Datasheet" "https://www.onsemi.com/pub/Collateral/NDS7002A-D.PDF"
			(at 66.04 283.21 0)
			(effects
				(font
					(size 1.27 1.27)
					(thickness 0.15)
				)
				(justify left bottom)
				(hide yes)
			)
		)
		(property "Description" "Power MOSFET, N Channel, 60 V, 115 mA, 1.2 ohm, SOT-23, Surface Mount"
			(at 43.18 270.51 0)
			(effects
				(font
					(size 1.27 1.27)
				)
				(hide yes)
			)
		)
		(property "MPN" "2N7002"
			(at 54.61 269.2399 0)
			(effects
				(font
					(size 1.27 1.27)
					(thickness 0.15)
				)
				(justify left)
			)
		)
		(property "Manufacturer" "ON Semiconductor"
			(at 66.04 288.29 0)
			(effects
				(font
					(size 1.27 1.27)
					(thickness 0.15)
				)
				(justify left bottom)
				(hide yes)
			)
		)
		(property "Author" "Antmicro"
			(at 66.04 290.83 0)
			(effects
				(font
					(size 1.27 1.27)
					(thickness 0.15)
				)
				(justify left bottom)
				(hide yes)
			)
		)
		(property "License" "Apache-2.0"
			(at 66.04 293.37 0)
			(effects
				(font
					(size 1.27 1.27)
					(thickness 0.15)
				)
				(justify left bottom)
				(hide yes)
			)
		)
		(pin "1"
		)
		(pin "2"
		)
		(pin "3"
		)
		(instances
			(project "artix-dc-scm"
				(path ""
					(reference "Q14")
					(unit 1)
				)
			)
		)
	)
	(symbol
		(lib_id "antmicropower:GND")
		(at 365.76 63.5 0)
		(mirror y)
		(unit 1)
		(exclude_from_sim no)
		(in_bom yes)
		(on_board yes)
		(dnp no)
		(property "Reference" "#PWR035"
			(at 365.76 69.85 0)
			(effects
				(font
					(size 1.27 1.27)
				)
				(hide yes)
			)
		)
		(property "Value" "GND"
			(at 365.76 67.31 0)
			(effects
				(font
					(size 1.27 1.27)
				)
			)
		)
		(property "Footprint" ""
			(at 365.76 63.5 0)
			(effects
				(font
					(size 1.27 1.27)
				)
				(hide yes)
			)
		)
		(property "Datasheet" ""
			(at 365.76 63.5 0)
			(effects
				(font
					(size 1.27 1.27)
				)
				(hide yes)
			)
		)
		(property "Description" ""
			(at 365.76 63.5 0)
			(effects
				(font
					(size 1.27 1.27)
				)
				(hide yes)
			)
		)
		(property "Author" "Antmicro"
			(at 356.87 71.12 0)
			(effects
				(font
					(size 1.27 1.27)
					(thickness 0.15)
				)
				(justify left bottom)
				(hide yes)
			)
		)
		(property "License" "Apache-2.0"
			(at 356.87 73.66 0)
			(effects
				(font
					(size 1.27 1.27)
					(thickness 0.15)
				)
				(justify left bottom)
				(hide yes)
			)
		)
		(pin "1"
		)
		(instances
			(project "artix-dc-scm"
				(path ""
					(reference "#PWR035")
					(unit 1)
				)
			)
		)
	)
	(symbol
		(lib_id "antmicropower:GND")
		(at 349.25 50.8 0)
		(mirror y)
		(unit 1)
		(exclude_from_sim no)
		(in_bom yes)
		(on_board yes)
		(dnp no)
		(property "Reference" "#PWR048"
			(at 349.25 57.15 0)
			(effects
				(font
					(size 1.27 1.27)
				)
				(hide yes)
			)
		)
		(property "Value" "GND"
			(at 349.25 54.61 0)
			(effects
				(font
					(size 1.27 1.27)
				)
			)
		)
		(property "Footprint" ""
			(at 349.25 50.8 0)
			(effects
				(font
					(size 1.27 1.27)
				)
				(hide yes)
			)
		)
		(property "Datasheet" ""
			(at 349.25 50.8 0)
			(effects
				(font
					(size 1.27 1.27)
				)
				(hide yes)
			)
		)
		(property "Description" ""
			(at 349.25 50.8 0)
			(effects
				(font
					(size 1.27 1.27)
				)
				(hide yes)
			)
		)
		(property "Author" "Antmicro"
			(at 340.36 58.42 0)
			(effects
				(font
					(size 1.27 1.27)
					(thickness 0.15)
				)
				(justify left bottom)
				(hide yes)
			)
		)
		(property "License" "Apache-2.0"
			(at 340.36 60.96 0)
			(effects
				(font
					(size 1.27 1.27)
					(thickness 0.15)
				)
				(justify left bottom)
				(hide yes)
			)
		)
		(pin "1"
		)
		(instances
			(project "artix-dc-scm"
				(path ""
					(reference "#PWR048")
					(unit 1)
				)
			)
		)
	)
	(symbol
		(lib_id "antmicroCapacitors0402:C_470n_0402")
		(at 356.87 63.5 270)
		(mirror x)
		(unit 1)
		(exclude_from_sim no)
		(in_bom yes)
		(on_board yes)
		(dnp no)
		(property "Reference" "C132"
			(at 356.235 59.055 90)
			(effects
				(font
					(size 1.27 1.27)
				)
				(justify right)
			)
		)
		(property "Value" "C_470n_0402"
			(at 346.71 43.18 0)
			(effects
				(font
					(size 1.27 1.27)
					(thickness 0.15)
				)
				(justify left bottom)
				(hide yes)
			)
		)
		(property "Footprint" "antmicro-footprints:C_0402_1005Metric"
			(at 344.17 43.18 0)
			(effects
				(font
					(size 1.27 1.27)
					(thickness 0.15)
				)
				(justify left bottom)
				(hide yes)
			)
		)
		(property "Datasheet" "https://product.tdk.com/en/search/capacitor/ceramic/mlcc/info?part_no=C1005X5R1E474M050BB"
			(at 341.63 43.18 0)
			(effects
				(font
					(size 1.27 1.27)
					(thickness 0.15)
				)
				(justify left bottom)
				(hide yes)
			)
		)
		(property "Description" "SMD Multilayer Ceramic Capacitor, 0.47 µF, 25 V, 0402 [1005 Metric], ± 20%, X5R, C"
			(at 356.87 63.5 0)
			(effects
				(font
					(size 1.27 1.27)
				)
				(hide yes)
			)
		)
		(property "Manufacturer" "TDK"
			(at 336.55 43.18 0)
			(effects
				(font
					(size 1.27 1.27)
					(thickness 0.15)
				)
				(justify left bottom)
				(hide yes)
			)
		)
		(property "MPN" "C1005X5R1E474M050BB"
			(at 339.09 43.18 0)
			(effects
				(font
					(size 1.27 1.27)
					(thickness 0.15)
				)
				(justify left bottom)
				(hide yes)
			)
		)
		(property "Val" "470n"
			(at 356.235 62.865 90)
			(effects
				(font
					(size 1.27 1.27)
					(thickness 0.15)
				)
				(justify right)
			)
		)
		(property "License" "Apache-2.0"
			(at 334.01 43.18 0)
			(effects
				(font
					(size 1.27 1.27)
					(thickness 0.15)
				)
				(justify left bottom)
				(hide yes)
			)
		)
		(property "Author" "Antmicro"
			(at 331.47 43.18 0)
			(effects
				(font
					(size 1.27 1.27)
					(thickness 0.15)
				)
				(justify left bottom)
				(hide yes)
			)
		)
		(property "Voltage" ""
			(at 328.93 43.18 0)
			(effects
				(font
					(size 1.27 1.27)
				)
				(justify left bottom)
				(hide yes)
			)
		)
		(property "Dielectric" ""
			(at 326.39 43.18 0)
			(effects
				(font
					(size 1.27 1.27)
				)
				(justify left bottom)
				(hide yes)
			)
		)
		(property "DNP" ""
			(at 356.87 63.5 0)
			(effects
				(font
					(size 1.27 1.27)
				)
			)
		)
		(pin "1"
		)
		(pin "2"
		)
		(instances
			(project "artix-dc-scm"
				(path ""
					(reference "C132")
					(unit 1)
				)
			)
		)
	)
	(symbol
		(lib_id "antmicroCapacitors0603:C_4u7_0603")
		(at 241.3 50.8 90)
		(unit 1)
		(exclude_from_sim no)
		(in_bom yes)
		(on_board yes)
		(dnp no)
		(property "Reference" "C97"
			(at 241.935 46.355 90)
			(effects
				(font
					(size 1.27 1.27)
				)
				(justify right)
			)
		)
		(property "Value" "C_4u7_0603"
			(at 251.46 30.48 0)
			(effects
				(font
					(size 1.27 1.27)
					(thickness 0.15)
				)
				(justify left bottom)
				(hide yes)
			)
		)
		(property "Footprint" "antmicro-footprints:C_0603_1608Metric"
			(at 254 30.48 0)
			(effects
				(font
					(size 1.27 1.27)
					(thickness 0.15)
				)
				(justify left bottom)
				(hide yes)
			)
		)
		(property "Datasheet" "https://product.tdk.com/en/search/capacitor/ceramic/mlcc/info?part_no=C1608X5R1V475M080AC"
			(at 256.54 30.48 0)
			(effects
				(font
					(size 1.27 1.27)
					(thickness 0.15)
				)
				(justify left bottom)
				(hide yes)
			)
		)
		(property "Description" "SMD Multilayer Ceramic Capacitor, 4.7 µF, 35 V, 0603 [1608 Metric], ± 20%, X5R, C"
			(at 241.3 50.8 0)
			(effects
				(font
					(size 1.27 1.27)
				)
				(hide yes)
			)
		)
		(property "Manufacturer" "TDK"
			(at 261.62 30.48 0)
			(effects
				(font
					(size 1.27 1.27)
					(thickness 0.15)
				)
				(justify left bottom)
				(hide yes)
			)
		)
		(property "MPN" "C1608X5R1V475M080AC"
			(at 259.08 30.48 0)
			(effects
				(font
					(size 1.27 1.27)
					(thickness 0.15)
				)
				(justify left bottom)
				(hide yes)
			)
		)
		(property "Val" "4u7"
			(at 241.935 50.165 90)
			(effects
				(font
					(size 1.27 1.27)
					(thickness 0.15)
				)
				(justify right)
			)
		)
		(property "License" "Apache-2.0"
			(at 264.16 30.48 0)
			(effects
				(font
					(size 1.27 1.27)
					(thickness 0.15)
				)
				(justify left bottom)
				(hide yes)
			)
		)
		(property "Author" "Antmicro"
			(at 266.7 30.48 0)
			(effects
				(font
					(size 1.27 1.27)
					(thickness 0.15)
				)
				(justify left bottom)
				(hide yes)
			)
		)
		(property "Voltage" ""
			(at 269.24 30.48 0)
			(effects
				(font
					(size 1.27 1.27)
				)
				(justify left bottom)
				(hide yes)
			)
		)
		(property "Dielectric" ""
			(at 271.78 30.48 0)
			(effects
				(font
					(size 1.27 1.27)
				)
				(justify left bottom)
				(hide yes)
			)
		)
		(pin "1"
		)
		(pin "2"
		)
		(instances
			(project "artix-dc-scm"
				(path ""
					(reference "C97")
					(unit 1)
				)
			)
		)
	)
	(symbol
		(lib_id "antmicropower:GND")
		(at 356.87 63.5 0)
		(mirror y)
		(unit 1)
		(exclude_from_sim no)
		(in_bom yes)
		(on_board yes)
		(dnp no)
		(property "Reference" "#PWR046"
			(at 356.87 69.85 0)
			(effects
				(font
					(size 1.27 1.27)
				)
				(hide yes)
			)
		)
		(property "Value" "GND"
			(at 356.87 67.31 0)
			(effects
				(font
					(size 1.27 1.27)
				)
			)
		)
		(property "Footprint" ""
			(at 356.87 63.5 0)
			(effects
				(font
					(size 1.27 1.27)
				)
				(hide yes)
			)
		)
		(property "Datasheet" ""
			(at 356.87 63.5 0)
			(effects
				(font
					(size 1.27 1.27)
				)
				(hide yes)
			)
		)
		(property "Description" ""
			(at 356.87 63.5 0)
			(effects
				(font
					(size 1.27 1.27)
				)
				(hide yes)
			)
		)
		(property "Author" "Antmicro"
			(at 347.98 71.12 0)
			(effects
				(font
					(size 1.27 1.27)
					(thickness 0.15)
				)
				(justify left bottom)
				(hide yes)
			)
		)
		(property "License" "Apache-2.0"
			(at 347.98 73.66 0)
			(effects
				(font
					(size 1.27 1.27)
					(thickness 0.15)
				)
				(justify left bottom)
				(hide yes)
			)
		)
		(pin "1"
		)
		(instances
			(project "artix-dc-scm"
				(path ""
					(reference "#PWR046")
					(unit 1)
				)
			)
		)
	)
	(symbol
		(lib_id "antmicroResistors0402:R_4k7_0402")
		(at 85.09 72.39 270)
		(unit 1)
		(exclude_from_sim no)
		(in_bom yes)
		(on_board yes)
		(dnp no)
		(property "Reference" "R89"
			(at 86.36 73.66 90)
			(effects
				(font
					(size 1.27 1.27)
				)
				(justify left)
			)
		)
		(property "Value" "R_4k7_0402"
			(at 72.39 92.71 0)
			(effects
				(font
					(size 1.27 1.27)
					(thickness 0.15)
				)
				(justify left bottom)
				(hide yes)
			)
		)
		(property "Footprint" "antmicro-footprints:R_0402_1005Metric"
			(at 69.85 92.71 0)
			(effects
				(font
					(size 1.27 1.27)
					(thickness 0.15)
				)
				(justify left bottom)
				(hide yes)
			)
		)
		(property "Datasheet" "https://www.bourns.com/docs/product-datasheets/cr.pdf"
			(at 67.31 92.71 0)
			(effects
				(font
					(size 1.27 1.27)
					(thickness 0.15)
				)
				(justify left bottom)
				(hide yes)
			)
		)
		(property "Description" "SMD Chip Resistor, 4.7 kohm, ± 1%, 62.5 mW, 0402 [1005 Metric], Thick Film, General Purpose"
			(at 85.09 72.39 0)
			(effects
				(font
					(size 1.27 1.27)
				)
				(hide yes)
			)
		)
		(property "Manufacturer" "Bourns"
			(at 62.23 92.71 0)
			(effects
				(font
					(size 1.27 1.27)
					(thickness 0.15)
				)
				(justify left bottom)
				(hide yes)
			)
		)
		(property "MPN" "CR0402-FX-4701GLF"
			(at 64.77 92.71 0)
			(effects
				(font
					(size 1.27 1.27)
					(thickness 0.15)
				)
				(justify left bottom)
				(hide yes)
			)
		)
		(property "Val" "4k7"
			(at 86.36 76.2 90)
			(effects
				(font
					(size 1.27 1.27)
					(thickness 0.15)
				)
				(justify left)
			)
		)
		(property "License" "Apache-2.0"
			(at 59.69 92.71 0)
			(effects
				(font
					(size 1.27 1.27)
					(thickness 0.15)
				)
				(justify left bottom)
				(hide yes)
			)
		)
		(property "Author" "Antmicro"
			(at 57.15 92.71 0)
			(effects
				(font
					(size 1.27 1.27)
					(thickness 0.15)
				)
				(justify left bottom)
				(hide yes)
			)
		)
		(property "Tolerance" "1%"
			(at 74.93 92.71 0)
			(effects
				(font
					(size 1.27 1.27)
				)
				(justify left bottom)
				(hide yes)
			)
		)
		(pin "1"
		)
		(pin "2"
		)
		(instances
			(project "artix-dc-scm"
				(path ""
					(reference "R89")
					(unit 1)
				)
			)
		)
	)
	(symbol
		(lib_id "antmicroResistors0402:R_100R_0402")
		(at 109.22 105.41 270)
		(unit 1)
		(exclude_from_sim no)
		(in_bom yes)
		(on_board yes)
		(dnp no)
		(property "Reference" "R87"
			(at 110.49 106.68 90)
			(effects
				(font
					(size 1.27 1.27)
				)
				(justify left)
			)
		)
		(property "Value" "R_100R_0402"
			(at 96.52 125.73 0)
			(effects
				(font
					(size 1.27 1.27)
					(thickness 0.15)
				)
				(justify left bottom)
				(hide yes)
			)
		)
		(property "Footprint" "antmicro-footprints:R_0402_1005Metric"
			(at 93.98 125.73 0)
			(effects
				(font
					(size 1.27 1.27)
					(thickness 0.15)
				)
				(justify left bottom)
				(hide yes)
			)
		)
		(property "Datasheet" "https://www.bourns.com/docs/product-datasheets/cr.pdf"
			(at 91.44 125.73 0)
			(effects
				(font
					(size 1.27 1.27)
					(thickness 0.15)
				)
				(justify left bottom)
				(hide yes)
			)
		)
		(property "Description" "SMD Chip Resistor, 100 ohm, ± 1%, 62.5 mW, 0402 [1005 Metric], Thick Film, General Purpose"
			(at 109.22 105.41 0)
			(effects
				(font
					(size 1.27 1.27)
				)
				(hide yes)
			)
		)
		(property "Manufacturer" "Bourns"
			(at 86.36 125.73 0)
			(effects
				(font
					(size 1.27 1.27)
					(thickness 0.15)
				)
				(justify left bottom)
				(hide yes)
			)
		)
		(property "MPN" "CR0402-FX-1000GLF"
			(at 88.9 125.73 0)
			(effects
				(font
					(size 1.27 1.27)
					(thickness 0.15)
				)
				(justify left bottom)
				(hide yes)
			)
		)
		(property "Val" "100R"
			(at 110.49 109.22 90)
			(effects
				(font
					(size 1.27 1.27)
					(thickness 0.15)
				)
				(justify left)
			)
		)
		(property "License" "Apache-2.0"
			(at 83.82 125.73 0)
			(effects
				(font
					(size 1.27 1.27)
					(thickness 0.15)
				)
				(justify left bottom)
				(hide yes)
			)
		)
		(property "Author" "Antmicro"
			(at 81.28 125.73 0)
			(effects
				(font
					(size 1.27 1.27)
					(thickness 0.15)
				)
				(justify left bottom)
				(hide yes)
			)
		)
		(property "Tolerance" "1%"
			(at 99.06 125.73 0)
			(effects
				(font
					(size 1.27 1.27)
				)
				(justify left bottom)
				(hide yes)
			)
		)
		(property "DNP" ""
			(at 109.22 107.95 0)
			(effects
				(font
					(size 1.27 1.27)
				)
			)
		)
		(pin "1"
		)
		(pin "2"
		)
		(instances
			(project "artix-dc-scm"
				(path ""
					(reference "R87")
					(unit 1)
				)
			)
		)
	)
	(symbol
		(lib_id "antmicropower:GND")
		(at 241.3 50.8 0)
		(unit 1)
		(exclude_from_sim no)
		(in_bom yes)
		(on_board yes)
		(dnp no)
		(property "Reference" "#PWR0316"
			(at 241.3 57.15 0)
			(effects
				(font
					(size 1.27 1.27)
				)
				(hide yes)
			)
		)
		(property "Value" "GND"
			(at 241.3 54.61 0)
			(effects
				(font
					(size 1.27 1.27)
				)
			)
		)
		(property "Footprint" ""
			(at 241.3 50.8 0)
			(effects
				(font
					(size 1.27 1.27)
				)
				(hide yes)
			)
		)
		(property "Datasheet" ""
			(at 241.3 50.8 0)
			(effects
				(font
					(size 1.27 1.27)
				)
				(hide yes)
			)
		)
		(property "Description" ""
			(at 241.3 50.8 0)
			(effects
				(font
					(size 1.27 1.27)
				)
				(hide yes)
			)
		)
		(property "Author" "Antmicro"
			(at 250.19 58.42 0)
			(effects
				(font
					(size 1.27 1.27)
					(thickness 0.15)
				)
				(justify left bottom)
				(hide yes)
			)
		)
		(property "License" "Apache-2.0"
			(at 250.19 60.96 0)
			(effects
				(font
					(size 1.27 1.27)
					(thickness 0.15)
				)
				(justify left bottom)
				(hide yes)
			)
		)
		(pin "1"
		)
		(instances
			(project "artix-dc-scm"
				(path ""
					(reference "#PWR0316")
					(unit 1)
				)
			)
		)
	)
	(symbol
		(lib_id "antmicroTransistorsFETsMOSFETsSingle:2N7002_SOT-23-3")
		(at 43.18 207.01 0)
		(unit 1)
		(exclude_from_sim no)
		(in_bom yes)
		(on_board yes)
		(dnp no)
		(fields_autoplaced yes)
		(property "Reference" "Q12"
			(at 54.61 203.1999 0)
			(effects
				(font
					(size 1.27 1.27)
				)
				(justify left)
			)
		)
		(property "Value" "2N7002_SOT-23-3"
			(at 57.785 204.47 90)
			(effects
				(font
					(size 1.27 1.27)
					(thickness 0.15)
				)
				(hide yes)
			)
		)
		(property "Footprint" "antmicro-footprints:SOT-23-3"
			(at 66.04 217.17 0)
			(effects
				(font
					(size 1.27 1.27)
					(thickness 0.15)
				)
				(justify left bottom)
				(hide yes)
			)
		)
		(property "Datasheet" "https://www.onsemi.com/pub/Collateral/NDS7002A-D.PDF"
			(at 66.04 219.71 0)
			(effects
				(font
					(size 1.27 1.27)
					(thickness 0.15)
				)
				(justify left bottom)
				(hide yes)
			)
		)
		(property "Description" "Power MOSFET, N Channel, 60 V, 115 mA, 1.2 ohm, SOT-23, Surface Mount"
			(at 43.18 207.01 0)
			(effects
				(font
					(size 1.27 1.27)
				)
				(hide yes)
			)
		)
		(property "MPN" "2N7002"
			(at 54.61 205.7399 0)
			(effects
				(font
					(size 1.27 1.27)
					(thickness 0.15)
				)
				(justify left)
			)
		)
		(property "Manufacturer" "ON Semiconductor"
			(at 66.04 224.79 0)
			(effects
				(font
					(size 1.27 1.27)
					(thickness 0.15)
				)
				(justify left bottom)
				(hide yes)
			)
		)
		(property "Author" "Antmicro"
			(at 66.04 227.33 0)
			(effects
				(font
					(size 1.27 1.27)
					(thickness 0.15)
				)
				(justify left bottom)
				(hide yes)
			)
		)
		(property "License" "Apache-2.0"
			(at 66.04 229.87 0)
			(effects
				(font
					(size 1.27 1.27)
					(thickness 0.15)
				)
				(justify left bottom)
				(hide yes)
			)
		)
		(pin "1"
		)
		(pin "2"
		)
		(pin "3"
		)
		(instances
			(project "artix-dc-scm"
				(path ""
					(reference "Q12")
					(unit 1)
				)
			)
		)
	)
	(symbol
		(lib_id "antmicropower:GND")
		(at 340.36 50.8 0)
		(mirror y)
		(unit 1)
		(exclude_from_sim no)
		(in_bom yes)
		(on_board yes)
		(dnp no)
		(property "Reference" "#PWR055"
			(at 340.36 57.15 0)
			(effects
				(font
					(size 1.27 1.27)
				)
				(hide yes)
			)
		)
		(property "Value" "GND"
			(at 340.36 54.61 0)
			(effects
				(font
					(size 1.27 1.27)
				)
			)
		)
		(property "Footprint" ""
			(at 340.36 50.8 0)
			(effects
				(font
					(size 1.27 1.27)
				)
				(hide yes)
			)
		)
		(property "Datasheet" ""
			(at 340.36 50.8 0)
			(effects
				(font
					(size 1.27 1.27)
				)
				(hide yes)
			)
		)
		(property "Description" ""
			(at 340.36 50.8 0)
			(effects
				(font
					(size 1.27 1.27)
				)
				(hide yes)
			)
		)
		(property "Author" "Antmicro"
			(at 331.47 58.42 0)
			(effects
				(font
					(size 1.27 1.27)
					(thickness 0.15)
				)
				(justify left bottom)
				(hide yes)
			)
		)
		(property "License" "Apache-2.0"
			(at 331.47 60.96 0)
			(effects
				(font
					(size 1.27 1.27)
					(thickness 0.15)
				)
				(justify left bottom)
				(hide yes)
			)
		)
		(pin "1"
		)
		(instances
			(project "artix-dc-scm"
				(path ""
					(reference "#PWR055")
					(unit 1)
				)
			)
		)
	)
	(symbol
		(lib_id "antmicropower:GND")
		(at 109.22 148.59 0)
		(unit 1)
		(exclude_from_sim no)
		(in_bom yes)
		(on_board yes)
		(dnp no)
		(property "Reference" "#PWR082"
			(at 109.22 154.94 0)
			(effects
				(font
					(size 1.27 1.27)
				)
				(hide yes)
			)
		)
		(property "Value" "GND"
			(at 109.22 152.4 0)
			(effects
				(font
					(size 1.27 1.27)
				)
			)
		)
		(property "Footprint" ""
			(at 109.22 148.59 0)
			(effects
				(font
					(size 1.27 1.27)
				)
				(hide yes)
			)
		)
		(property "Datasheet" ""
			(at 109.22 148.59 0)
			(effects
				(font
					(size 1.27 1.27)
				)
				(hide yes)
			)
		)
		(property "Description" ""
			(at 109.22 148.59 0)
			(effects
				(font
					(size 1.27 1.27)
				)
				(hide yes)
			)
		)
		(property "Author" "Antmicro"
			(at 118.11 156.21 0)
			(effects
				(font
					(size 1.27 1.27)
					(thickness 0.15)
				)
				(justify left bottom)
				(hide yes)
			)
		)
		(property "License" "Apache-2.0"
			(at 118.11 158.75 0)
			(effects
				(font
					(size 1.27 1.27)
					(thickness 0.15)
				)
				(justify left bottom)
				(hide yes)
			)
		)
		(pin "1"
		)
		(instances
			(project "artix-dc-scm"
				(path ""
					(reference "#PWR082")
					(unit 1)
				)
			)
		)
	)
	(symbol
		(lib_id "antmicropower:GND")
		(at 50.8 274.32 0)
		(unit 1)
		(exclude_from_sim no)
		(in_bom yes)
		(on_board yes)
		(dnp no)
		(property "Reference" "#PWR0324"
			(at 50.8 280.67 0)
			(effects
				(font
					(size 1.27 1.27)
				)
				(hide yes)
			)
		)
		(property "Value" "GND"
			(at 50.8 278.13 0)
			(effects
				(font
					(size 1.27 1.27)
				)
			)
		)
		(property "Footprint" ""
			(at 50.8 274.32 0)
			(effects
				(font
					(size 1.27 1.27)
				)
				(hide yes)
			)
		)
		(property "Datasheet" ""
			(at 50.8 274.32 0)
			(effects
				(font
					(size 1.27 1.27)
				)
				(hide yes)
			)
		)
		(property "Description" ""
			(at 50.8 274.32 0)
			(effects
				(font
					(size 1.27 1.27)
				)
				(hide yes)
			)
		)
		(property "Author" "Antmicro"
			(at 59.69 281.94 0)
			(effects
				(font
					(size 1.27 1.27)
					(thickness 0.15)
				)
				(justify left bottom)
				(hide yes)
			)
		)
		(property "License" "Apache-2.0"
			(at 59.69 284.48 0)
			(effects
				(font
					(size 1.27 1.27)
					(thickness 0.15)
				)
				(justify left bottom)
				(hide yes)
			)
		)
		(pin "1"
		)
		(instances
			(project "artix-dc-scm"
				(path ""
					(reference "#PWR0324")
					(unit 1)
				)
			)
		)
	)
	(symbol
		(lib_id "antmicropower:GND")
		(at 109.22 115.57 0)
		(unit 1)
		(exclude_from_sim no)
		(in_bom yes)
		(on_board yes)
		(dnp no)
		(property "Reference" "#PWR085"
			(at 109.22 121.92 0)
			(effects
				(font
					(size 1.27 1.27)
				)
				(hide yes)
			)
		)
		(property "Value" "GND"
			(at 109.22 119.38 0)
			(effects
				(font
					(size 1.27 1.27)
				)
			)
		)
		(property "Footprint" ""
			(at 109.22 115.57 0)
			(effects
				(font
					(size 1.27 1.27)
				)
				(hide yes)
			)
		)
		(property "Datasheet" ""
			(at 109.22 115.57 0)
			(effects
				(font
					(size 1.27 1.27)
				)
				(hide yes)
			)
		)
		(property "Description" ""
			(at 109.22 115.57 0)
			(effects
				(font
					(size 1.27 1.27)
				)
				(hide yes)
			)
		)
		(property "Author" "Antmicro"
			(at 118.11 123.19 0)
			(effects
				(font
					(size 1.27 1.27)
					(thickness 0.15)
				)
				(justify left bottom)
				(hide yes)
			)
		)
		(property "License" "Apache-2.0"
			(at 118.11 125.73 0)
			(effects
				(font
					(size 1.27 1.27)
					(thickness 0.15)
				)
				(justify left bottom)
				(hide yes)
			)
		)
		(pin "1"
		)
		(instances
			(project "artix-dc-scm"
				(path ""
					(reference "#PWR085")
					(unit 1)
				)
			)
		)
	)
	(symbol
		(lib_id "antmicropower:GND")
		(at 140.97 151.13 0)
		(unit 1)
		(exclude_from_sim no)
		(in_bom yes)
		(on_board yes)
		(dnp no)
		(property "Reference" "#PWR080"
			(at 140.97 157.48 0)
			(effects
				(font
					(size 1.27 1.27)
				)
				(hide yes)
			)
		)
		(property "Value" "GND"
			(at 140.97 154.94 0)
			(effects
				(font
					(size 1.27 1.27)
				)
			)
		)
		(property "Footprint" ""
			(at 140.97 151.13 0)
			(effects
				(font
					(size 1.27 1.27)
				)
				(hide yes)
			)
		)
		(property "Datasheet" ""
			(at 140.97 151.13 0)
			(effects
				(font
					(size 1.27 1.27)
				)
				(hide yes)
			)
		)
		(property "Description" ""
			(at 140.97 151.13 0)
			(effects
				(font
					(size 1.27 1.27)
				)
				(hide yes)
			)
		)
		(property "Author" "Antmicro"
			(at 149.86 158.75 0)
			(effects
				(font
					(size 1.27 1.27)
					(thickness 0.15)
				)
				(justify left bottom)
				(hide yes)
			)
		)
		(property "License" "Apache-2.0"
			(at 149.86 161.29 0)
			(effects
				(font
					(size 1.27 1.27)
					(thickness 0.15)
				)
				(justify left bottom)
				(hide yes)
			)
		)
		(pin "1"
		)
		(instances
			(project "artix-dc-scm"
				(path ""
					(reference "#PWR080")
					(unit 1)
				)
			)
		)
	)
	(symbol
		(lib_id "antmicroCapacitors0603:C_4u7_0603")
		(at 365.76 50.8 270)
		(mirror x)
		(unit 1)
		(exclude_from_sim no)
		(in_bom yes)
		(on_board yes)
		(dnp no)
		(property "Reference" "C102"
			(at 365.125 46.355 90)
			(effects
				(font
					(size 1.27 1.27)
				)
				(justify right)
			)
		)
		(property "Value" "C_4u7_0603"
			(at 355.6 30.48 0)
			(effects
				(font
					(size 1.27 1.27)
					(thickness 0.15)
				)
				(justify left bottom)
				(hide yes)
			)
		)
		(property "Footprint" "antmicro-footprints:C_0603_1608Metric"
			(at 353.06 30.48 0)
			(effects
				(font
					(size 1.27 1.27)
					(thickness 0.15)
				)
				(justify left bottom)
				(hide yes)
			)
		)
		(property "Datasheet" "https://product.tdk.com/en/search/capacitor/ceramic/mlcc/info?part_no=C1608X5R1V475M080AC"
			(at 350.52 30.48 0)
			(effects
				(font
					(size 1.27 1.27)
					(thickness 0.15)
				)
				(justify left bottom)
				(hide yes)
			)
		)
		(property "Description" "SMD Multilayer Ceramic Capacitor, 4.7 µF, 35 V, 0603 [1608 Metric], ± 20%, X5R, C"
			(at 365.76 50.8 0)
			(effects
				(font
					(size 1.27 1.27)
				)
				(hide yes)
			)
		)
		(property "Manufacturer" "TDK"
			(at 345.44 30.48 0)
			(effects
				(font
					(size 1.27 1.27)
					(thickness 0.15)
				)
				(justify left bottom)
				(hide yes)
			)
		)
		(property "MPN" "C1608X5R1V475M080AC"
			(at 347.98 30.48 0)
			(effects
				(font
					(size 1.27 1.27)
					(thickness 0.15)
				)
				(justify left bottom)
				(hide yes)
			)
		)
		(property "Val" "4u7"
			(at 365.125 50.165 90)
			(effects
				(font
					(size 1.27 1.27)
					(thickness 0.15)
				)
				(justify right)
			)
		)
		(property "License" "Apache-2.0"
			(at 342.9 30.48 0)
			(effects
				(font
					(size 1.27 1.27)
					(thickness 0.15)
				)
				(justify left bottom)
				(hide yes)
			)
		)
		(property "Author" "Antmicro"
			(at 340.36 30.48 0)
			(effects
				(font
					(size 1.27 1.27)
					(thickness 0.15)
				)
				(justify left bottom)
				(hide yes)
			)
		)
		(property "Voltage" ""
			(at 337.82 30.48 0)
			(effects
				(font
					(size 1.27 1.27)
				)
				(justify left bottom)
				(hide yes)
			)
		)
		(property "Dielectric" ""
			(at 335.28 30.48 0)
			(effects
				(font
					(size 1.27 1.27)
				)
				(justify left bottom)
				(hide yes)
			)
		)
		(pin "1"
		)
		(pin "2"
		)
		(instances
			(project "artix-dc-scm"
				(path ""
					(reference "C102")
					(unit 1)
				)
			)
		)
	)
	(symbol
		(lib_id "antmicroCapacitorsmisc:C_47u_1210")
		(at 373.38 50.8 270)
		(mirror x)
		(unit 1)
		(exclude_from_sim no)
		(in_bom yes)
		(on_board yes)
		(dnp no)
		(property "Reference" "C96"
			(at 372.745 46.355 90)
			(effects
				(font
					(size 1.27 1.27)
				)
				(justify right)
			)
		)
		(property "Value" "C_47u_1210"
			(at 363.22 30.48 0)
			(effects
				(font
					(size 1.27 1.27)
					(thickness 0.15)
				)
				(justify left bottom)
				(hide yes)
			)
		)
		(property "Footprint" "antmicro-footprints:C_1210_3225Metric"
			(at 360.68 30.48 0)
			(effects
				(font
					(size 1.27 1.27)
					(thickness 0.15)
				)
				(justify left bottom)
				(hide yes)
			)
		)
		(property "Datasheet" "https://www.kemet.com/en/us/capacitors/product/C1210C476K8RACTU.html"
			(at 358.14 30.48 0)
			(effects
				(font
					(size 1.27 1.27)
					(thickness 0.15)
				)
				(justify left bottom)
				(hide yes)
			)
		)
		(property "Description" "SMD Multilayer Ceramic Capacitor, 47 µF, 10 V, 1210 [3225 Metric], ± 10%, X7R, C Series KEMET"
			(at 373.38 50.8 0)
			(effects
				(font
					(size 1.27 1.27)
				)
				(hide yes)
			)
		)
		(property "Manufacturer" "KEMET"
			(at 353.06 30.48 0)
			(effects
				(font
					(size 1.27 1.27)
					(thickness 0.15)
				)
				(justify left bottom)
				(hide yes)
			)
		)
		(property "MPN" "C1210C476K8RACTU"
			(at 355.6 30.48 0)
			(effects
				(font
					(size 1.27 1.27)
					(thickness 0.15)
				)
				(justify left bottom)
				(hide yes)
			)
		)
		(property "Val" "47u"
			(at 372.745 50.165 90)
			(effects
				(font
					(size 1.27 1.27)
					(thickness 0.15)
				)
				(justify right)
			)
		)
		(property "License" "Apache-2.0"
			(at 350.52 30.48 0)
			(effects
				(font
					(size 1.27 1.27)
					(thickness 0.15)
				)
				(justify left bottom)
				(hide yes)
			)
		)
		(property "Author" "Antmicro"
			(at 347.98 30.48 0)
			(effects
				(font
					(size 1.27 1.27)
					(thickness 0.15)
				)
				(justify left bottom)
				(hide yes)
			)
		)
		(property "Voltage" ""
			(at 345.44 30.48 0)
			(effects
				(font
					(size 1.27 1.27)
				)
				(justify left bottom)
				(hide yes)
			)
		)
		(property "Dielectric" ""
			(at 342.9 30.48 0)
			(effects
				(font
					(size 1.27 1.27)
				)
				(justify left bottom)
				(hide yes)
			)
		)
		(property "Public" "False"
			(at 340.36 30.48 0)
			(effects
				(font
					(size 1.27 1.27)
				)
				(justify left bottom)
				(hide yes)
			)
		)
		(pin "1"
		)
		(pin "2"
		)
		(instances
			(project "artix-dc-scm"
				(path ""
					(reference "C96")
					(unit 1)
				)
			)
		)
	)
)
